FILE_TYPE = MACRO_DRAWING;
SET COLOR_WIRE YELLOW;
SET COLOR_PROP MONO;
SET COLOR_DOT WHITE;
SET COLOR_ARC YELLOW;
SET COLOR_BODY GREEN;
SET COLOR_NOTE MONO;
SET PROP_DISPLAY VALUE;
SET PAGE_NUMBER P83;
FORCEADD OFFPAGE..3
(1600 5250);
FORCEPROP 2 LAST $XR0 60 
J 0
(1814 5250);
DISPLAY 0.638298 (1814 5250);
PAINT MONO (1814 5250);
FORCEPROP 2 LAST $XR1 84 
J 0
(1904 5250);
DISPLAY 0.638298 (1904 5250);
PAINT MONO (1904 5250);
FORCEPROP 2 LAST CDS_LIB mstr_standard
J 0
(1600 5250);
DISPLAY 0.787234 (1600 5250);
PAINT MONO (1600 5250);
DISPLAY INVISIBLE (1600 5250);
FORCEPROP 1 LAST OFFPAGE TRUE
J 0
(1925 5125);
DISPLAY 0.936170 (1925 5125);
PAINT GREEN (1925 5125);
DISPLAY INVISIBLE (1925 5125);
FORCEPROP 1 LAST COMMENT_BODY TRUE
J 0
(1550 5150);
DISPLAY 0.936170 (1550 5150);
PAINT GREEN (1550 5150);
DISPLAY INVISIBLE (1550 5150);
FORCEPROP 2 LAST PATH I1
J 0
(1800 5325);
DISPLAY 0.787234 (1800 5325);
PAINT MONO (1800 5325);
DISPLAY INVISIBLE (1800 5325);
FORCEADD TAP..6
R 2
(700 4900);
FORCEPROP 3 LASTPIN (650 4900) SIG_NAME M_K_DQS_DP<14>
J 0
(660 4910);
DISPLAY 0.659574 (660 4910);
PAINT MONO (660 4910);
DISPLAY INVISIBLE (660 4910);
FORCEPROP 1 LASTPIN (650 4900) BN 14
J 2
(700 4910);
DISPLAY 0.617021 (700 4910);
PAINT PINK (700 4910);
FORCEPROP 2 LAST CDS_LIB mstr_standard
J 0
(700 4900);
DISPLAY 0.787234 (700 4900);
PAINT MONO (700 4900);
DISPLAY INVISIBLE (700 4900);
FORCEPROP 1 LAST BODY_TYPE PLUMBING
J 2
(700 4850);
DISPLAY 1.234043 (700 4850);
PAINT GREEN (700 4850);
DISPLAY INVISIBLE (700 4850);
FORCEPROP 1 LAST HDL_TAP TRUE
J 2
(375 4775);
DISPLAY 1.234043 (375 4775);
PAINT GREEN (375 4775);
DISPLAY INVISIBLE (375 4775);
FORCEPROP 1 LAST PATH I10
J 2
(700 4900);
DISPLAY 0.936170 (700 4900);
PAINT GREEN (700 4900);
DISPLAY INVISIBLE (700 4900);
FORCEADD TAP..6
R 2
(-1700 2150);
FORCEPROP 3 LASTPIN (-1750 2150) SIG_NAME M_K_DQ<8>
J 0
(-1740 2160);
DISPLAY 0.659574 (-1740 2160);
PAINT MONO (-1740 2160);
DISPLAY INVISIBLE (-1740 2160);
FORCEPROP 1 LASTPIN (-1750 2150) BN 8
J 2
(-1700 2160);
DISPLAY 0.617021 (-1700 2160);
PAINT PINK (-1700 2160);
FORCEPROP 2 LAST CDS_LIB mstr_standard
J 2
(-1700 2150);
DISPLAY 0.787234 (-1700 2150);
PAINT MONO (-1700 2150);
DISPLAY INVISIBLE (-1700 2150);
FORCEPROP 1 LAST BODY_TYPE PLUMBING
J 2
(-1700 2100);
DISPLAY 1.234043 (-1700 2100);
PAINT GREEN (-1700 2100);
DISPLAY INVISIBLE (-1700 2100);
FORCEPROP 1 LAST HDL_TAP TRUE
J 2
(-2025 2025);
DISPLAY 1.234043 (-2025 2025);
PAINT GREEN (-2025 2025);
DISPLAY INVISIBLE (-2025 2025);
FORCEPROP 1 LAST PATH I100
J 2
(-1700 2150);
DISPLAY 0.936170 (-1700 2150);
PAINT GREEN (-1700 2150);
DISPLAY INVISIBLE (-1700 2150);
FORCEADD TAP..6
R 2
(-1700 2200);
FORCEPROP 3 LASTPIN (-1750 2200) SIG_NAME M_K_DQ<11>
J 0
(-1740 2210);
DISPLAY 0.659574 (-1740 2210);
PAINT MONO (-1740 2210);
DISPLAY INVISIBLE (-1740 2210);
FORCEPROP 1 LASTPIN (-1750 2200) BN 11
J 2
(-1700 2210);
DISPLAY 0.617021 (-1700 2210);
PAINT PINK (-1700 2210);
FORCEPROP 2 LAST CDS_LIB mstr_standard
J 2
(-1700 2200);
DISPLAY 0.787234 (-1700 2200);
PAINT MONO (-1700 2200);
DISPLAY INVISIBLE (-1700 2200);
FORCEPROP 1 LAST BODY_TYPE PLUMBING
J 2
(-1700 2150);
DISPLAY 1.234043 (-1700 2150);
PAINT GREEN (-1700 2150);
DISPLAY INVISIBLE (-1700 2150);
FORCEPROP 1 LAST HDL_TAP TRUE
J 2
(-2025 2075);
DISPLAY 1.234043 (-2025 2075);
PAINT GREEN (-2025 2075);
DISPLAY INVISIBLE (-2025 2075);
FORCEPROP 1 LAST PATH I101
J 2
(-1700 2200);
DISPLAY 0.936170 (-1700 2200);
PAINT GREEN (-1700 2200);
DISPLAY INVISIBLE (-1700 2200);
FORCEADD TAP..6
R 2
(-1700 1900);
FORCEPROP 3 LASTPIN (-1750 1900) SIG_NAME M_K_DQ<5>
J 0
(-1740 1910);
DISPLAY 0.659574 (-1740 1910);
PAINT MONO (-1740 1910);
DISPLAY INVISIBLE (-1740 1910);
FORCEPROP 1 LASTPIN (-1750 1900) BN 5
J 2
(-1700 1910);
DISPLAY 0.617021 (-1700 1910);
PAINT PINK (-1700 1910);
FORCEPROP 2 LAST CDS_LIB mstr_standard
J 2
(-1700 1900);
DISPLAY 0.787234 (-1700 1900);
PAINT MONO (-1700 1900);
DISPLAY INVISIBLE (-1700 1900);
FORCEPROP 1 LAST BODY_TYPE PLUMBING
J 2
(-1700 1850);
DISPLAY 1.234043 (-1700 1850);
PAINT GREEN (-1700 1850);
DISPLAY INVISIBLE (-1700 1850);
FORCEPROP 1 LAST HDL_TAP TRUE
J 2
(-2025 1775);
DISPLAY 1.234043 (-2025 1775);
PAINT GREEN (-2025 1775);
DISPLAY INVISIBLE (-2025 1775);
FORCEPROP 1 LAST PATH I102
J 2
(-1700 1900);
DISPLAY 0.936170 (-1700 1900);
PAINT GREEN (-1700 1900);
DISPLAY INVISIBLE (-1700 1900);
FORCEADD TAP..6
R 2
(-1700 1850);
FORCEPROP 3 LASTPIN (-1750 1850) SIG_NAME M_K_DQ<2>
J 0
(-1740 1860);
DISPLAY 0.659574 (-1740 1860);
PAINT MONO (-1740 1860);
DISPLAY INVISIBLE (-1740 1860);
FORCEPROP 1 LASTPIN (-1750 1850) BN 2
J 2
(-1700 1860);
DISPLAY 0.617021 (-1700 1860);
PAINT PINK (-1700 1860);
FORCEPROP 2 LAST CDS_LIB mstr_standard
J 2
(-1700 1850);
DISPLAY 0.787234 (-1700 1850);
PAINT MONO (-1700 1850);
DISPLAY INVISIBLE (-1700 1850);
FORCEPROP 1 LAST BODY_TYPE PLUMBING
J 2
(-1700 1800);
DISPLAY 1.234043 (-1700 1800);
PAINT GREEN (-1700 1800);
DISPLAY INVISIBLE (-1700 1800);
FORCEPROP 1 LAST HDL_TAP TRUE
J 2
(-2025 1725);
DISPLAY 1.234043 (-2025 1725);
PAINT GREEN (-2025 1725);
DISPLAY INVISIBLE (-2025 1725);
FORCEPROP 1 LAST PATH I103
J 2
(-1700 1850);
DISPLAY 0.936170 (-1700 1850);
PAINT GREEN (-1700 1850);
DISPLAY INVISIBLE (-1700 1850);
FORCEADD TAP..6
R 2
(-1700 1950);
FORCEPROP 3 LASTPIN (-1750 1950) SIG_NAME M_K_DQ<4>
J 0
(-1740 1960);
DISPLAY 0.659574 (-1740 1960);
PAINT MONO (-1740 1960);
DISPLAY INVISIBLE (-1740 1960);
FORCEPROP 1 LASTPIN (-1750 1950) BN 4
J 2
(-1700 1960);
DISPLAY 0.617021 (-1700 1960);
PAINT PINK (-1700 1960);
FORCEPROP 2 LAST CDS_LIB mstr_standard
J 2
(-1700 1950);
DISPLAY 0.787234 (-1700 1950);
PAINT MONO (-1700 1950);
DISPLAY INVISIBLE (-1700 1950);
FORCEPROP 1 LAST BODY_TYPE PLUMBING
J 2
(-1700 1900);
DISPLAY 1.234043 (-1700 1900);
PAINT GREEN (-1700 1900);
DISPLAY INVISIBLE (-1700 1900);
FORCEPROP 1 LAST HDL_TAP TRUE
J 2
(-2025 1825);
DISPLAY 1.234043 (-2025 1825);
PAINT GREEN (-2025 1825);
DISPLAY INVISIBLE (-2025 1825);
FORCEPROP 1 LAST PATH I104
J 2
(-1700 1950);
DISPLAY 0.936170 (-1700 1950);
PAINT GREEN (-1700 1950);
DISPLAY INVISIBLE (-1700 1950);
FORCEADD TAP..6
R 2
(-1700 2000);
FORCEPROP 3 LASTPIN (-1750 2000) SIG_NAME M_K_DQ<7>
J 0
(-1740 2010);
DISPLAY 0.659574 (-1740 2010);
PAINT MONO (-1740 2010);
DISPLAY INVISIBLE (-1740 2010);
FORCEPROP 1 LASTPIN (-1750 2000) BN 7
J 2
(-1700 2010);
DISPLAY 0.617021 (-1700 2010);
PAINT PINK (-1700 2010);
FORCEPROP 2 LAST CDS_LIB mstr_standard
J 2
(-1700 2000);
DISPLAY 0.787234 (-1700 2000);
PAINT MONO (-1700 2000);
DISPLAY INVISIBLE (-1700 2000);
FORCEPROP 1 LAST BODY_TYPE PLUMBING
J 2
(-1700 1950);
DISPLAY 1.234043 (-1700 1950);
PAINT GREEN (-1700 1950);
DISPLAY INVISIBLE (-1700 1950);
FORCEPROP 1 LAST HDL_TAP TRUE
J 2
(-2025 1875);
DISPLAY 1.234043 (-2025 1875);
PAINT GREEN (-2025 1875);
DISPLAY INVISIBLE (-2025 1875);
FORCEPROP 1 LAST PATH I105
J 2
(-1700 2000);
DISPLAY 0.936170 (-1700 2000);
PAINT GREEN (-1700 2000);
DISPLAY INVISIBLE (-1700 2000);
FORCEADD TAP..6
R 2
(-1700 2100);
FORCEPROP 3 LASTPIN (-1750 2100) SIG_NAME M_K_DQ<9>
J 0
(-1740 2110);
DISPLAY 0.659574 (-1740 2110);
PAINT MONO (-1740 2110);
DISPLAY INVISIBLE (-1740 2110);
FORCEPROP 1 LASTPIN (-1750 2100) BN 9
J 2
(-1700 2110);
DISPLAY 0.617021 (-1700 2110);
PAINT PINK (-1700 2110);
FORCEPROP 2 LAST CDS_LIB mstr_standard
J 2
(-1700 2100);
DISPLAY 0.787234 (-1700 2100);
PAINT MONO (-1700 2100);
DISPLAY INVISIBLE (-1700 2100);
FORCEPROP 1 LAST BODY_TYPE PLUMBING
J 2
(-1700 2050);
DISPLAY 1.234043 (-1700 2050);
PAINT GREEN (-1700 2050);
DISPLAY INVISIBLE (-1700 2050);
FORCEPROP 1 LAST HDL_TAP TRUE
J 2
(-2025 1975);
DISPLAY 1.234043 (-2025 1975);
PAINT GREEN (-2025 1975);
DISPLAY INVISIBLE (-2025 1975);
FORCEPROP 1 LAST PATH I106
J 2
(-1700 2100);
DISPLAY 0.936170 (-1700 2100);
PAINT GREEN (-1700 2100);
DISPLAY INVISIBLE (-1700 2100);
FORCEADD TAP..6
R 2
(-1700 2050);
FORCEPROP 3 LASTPIN (-1750 2050) SIG_NAME M_K_DQ<6>
J 0
(-1740 2060);
DISPLAY 0.659574 (-1740 2060);
PAINT MONO (-1740 2060);
DISPLAY INVISIBLE (-1740 2060);
FORCEPROP 1 LASTPIN (-1750 2050) BN 6
J 2
(-1700 2060);
DISPLAY 0.617021 (-1700 2060);
PAINT PINK (-1700 2060);
FORCEPROP 2 LAST CDS_LIB mstr_standard
J 2
(-1700 2050);
DISPLAY 0.787234 (-1700 2050);
PAINT MONO (-1700 2050);
DISPLAY INVISIBLE (-1700 2050);
FORCEPROP 1 LAST BODY_TYPE PLUMBING
J 2
(-1700 2000);
DISPLAY 1.234043 (-1700 2000);
PAINT GREEN (-1700 2000);
DISPLAY INVISIBLE (-1700 2000);
FORCEPROP 1 LAST HDL_TAP TRUE
J 2
(-2025 1925);
DISPLAY 1.234043 (-2025 1925);
PAINT GREEN (-2025 1925);
DISPLAY INVISIBLE (-2025 1925);
FORCEPROP 1 LAST PATH I107
J 2
(-1700 2050);
DISPLAY 0.936170 (-1700 2050);
PAINT GREEN (-1700 2050);
DISPLAY INVISIBLE (-1700 2050);
FORCEADD TAP..6
R 2
(-1700 1700);
FORCEPROP 3 LASTPIN (-1750 1700) SIG_NAME M_K_DQ<1>
J 0
(-1740 1710);
DISPLAY 0.659574 (-1740 1710);
PAINT MONO (-1740 1710);
DISPLAY INVISIBLE (-1740 1710);
FORCEPROP 1 LASTPIN (-1750 1700) BN 1
J 2
(-1700 1710);
DISPLAY 0.617021 (-1700 1710);
PAINT PINK (-1700 1710);
FORCEPROP 2 LAST CDS_LIB mstr_standard
J 2
(-1700 1700);
DISPLAY 0.787234 (-1700 1700);
PAINT MONO (-1700 1700);
DISPLAY INVISIBLE (-1700 1700);
FORCEPROP 1 LAST BODY_TYPE PLUMBING
J 2
(-1700 1650);
DISPLAY 1.234043 (-1700 1650);
PAINT GREEN (-1700 1650);
DISPLAY INVISIBLE (-1700 1650);
FORCEPROP 1 LAST HDL_TAP TRUE
J 2
(-2025 1575);
DISPLAY 1.234043 (-2025 1575);
PAINT GREEN (-2025 1575);
DISPLAY INVISIBLE (-2025 1575);
FORCEPROP 1 LAST PATH I108
J 2
(-1700 1700);
DISPLAY 0.936170 (-1700 1700);
PAINT GREEN (-1700 1700);
DISPLAY INVISIBLE (-1700 1700);
FORCEADD TAP..6
R 2
(-1700 1800);
FORCEPROP 3 LASTPIN (-1750 1800) SIG_NAME M_K_DQ<3>
J 0
(-1740 1810);
DISPLAY 0.659574 (-1740 1810);
PAINT MONO (-1740 1810);
DISPLAY INVISIBLE (-1740 1810);
FORCEPROP 1 LASTPIN (-1750 1800) BN 3
J 2
(-1700 1810);
DISPLAY 0.617021 (-1700 1810);
PAINT PINK (-1700 1810);
FORCEPROP 2 LAST CDS_LIB mstr_standard
J 2
(-1700 1800);
DISPLAY 0.787234 (-1700 1800);
PAINT MONO (-1700 1800);
DISPLAY INVISIBLE (-1700 1800);
FORCEPROP 1 LAST BODY_TYPE PLUMBING
J 2
(-1700 1750);
DISPLAY 1.234043 (-1700 1750);
PAINT GREEN (-1700 1750);
DISPLAY INVISIBLE (-1700 1750);
FORCEPROP 1 LAST HDL_TAP TRUE
J 2
(-2025 1675);
DISPLAY 1.234043 (-2025 1675);
PAINT GREEN (-2025 1675);
DISPLAY INVISIBLE (-2025 1675);
FORCEPROP 1 LAST PATH I109
J 2
(-1700 1800);
DISPLAY 0.936170 (-1700 1800);
PAINT GREEN (-1700 1800);
DISPLAY INVISIBLE (-1700 1800);
FORCEADD TAP..6
R 2
(700 5000);
FORCEPROP 3 LASTPIN (650 5000) SIG_NAME M_K_DQS_DP<15>
J 0
(660 5010);
DISPLAY 0.659574 (660 5010);
PAINT MONO (660 5010);
DISPLAY INVISIBLE (660 5010);
FORCEPROP 1 LASTPIN (650 5000) BN 15
J 2
(700 5010);
DISPLAY 0.617021 (700 5010);
PAINT PINK (700 5010);
FORCEPROP 2 LAST CDS_LIB mstr_standard
J 0
(700 5000);
DISPLAY 0.787234 (700 5000);
PAINT MONO (700 5000);
DISPLAY INVISIBLE (700 5000);
FORCEPROP 1 LAST BODY_TYPE PLUMBING
J 2
(700 4950);
DISPLAY 1.234043 (700 4950);
PAINT GREEN (700 4950);
DISPLAY INVISIBLE (700 4950);
FORCEPROP 1 LAST HDL_TAP TRUE
J 2
(375 4875);
DISPLAY 1.234043 (375 4875);
PAINT GREEN (375 4875);
DISPLAY INVISIBLE (375 4875);
FORCEPROP 1 LAST PATH I11
J 2
(700 5000);
DISPLAY 0.936170 (700 5000);
PAINT GREEN (700 5000);
DISPLAY INVISIBLE (700 5000);
FORCEADD TAP..6
R 2
(-1700 1750);
FORCEPROP 3 LASTPIN (-1750 1750) SIG_NAME M_K_DQ<0>
J 0
(-1740 1760);
DISPLAY 0.659574 (-1740 1760);
PAINT MONO (-1740 1760);
DISPLAY INVISIBLE (-1740 1760);
FORCEPROP 1 LASTPIN (-1750 1750) BN 0
J 2
(-1700 1760);
DISPLAY 0.617021 (-1700 1760);
PAINT PINK (-1700 1760);
FORCEPROP 2 LAST CDS_LIB mstr_standard
J 2
(-1700 1750);
DISPLAY 0.787234 (-1700 1750);
PAINT MONO (-1700 1750);
DISPLAY INVISIBLE (-1700 1750);
FORCEPROP 1 LAST BODY_TYPE PLUMBING
J 2
(-1700 1700);
DISPLAY 1.234043 (-1700 1700);
PAINT GREEN (-1700 1700);
DISPLAY INVISIBLE (-1700 1700);
FORCEPROP 1 LAST HDL_TAP TRUE
J 2
(-2025 1625);
DISPLAY 1.234043 (-2025 1625);
PAINT GREEN (-2025 1625);
DISPLAY INVISIBLE (-2025 1625);
FORCEPROP 1 LAST PATH I110
J 2
(-1700 1750);
DISPLAY 0.936170 (-1700 1750);
PAINT GREEN (-1700 1750);
DISPLAY INVISIBLE (-1700 1750);
FORCEADD SCONN288_H44441004..1
(-2450 3200);
FORCEPROP 1 LAST LOCATION J1B1
J 0
(-2900 5100);
DISPLAY 0.617021 (-2900 5100);
PAINT AQUA (-2900 5100);
FORCEPROP 1 LAST PART_NUMBER H44441-004
J 0
(-2900 1200);
DISPLAY 0.617021 (-2900 1200);
PAINT BLUE (-2900 1200);
FORCEPROP 1 LAST MATERIAL SCONN
J 0
(-2900 5050);
DISPLAY 0.617021 (-2900 5050);
PAINT SKYBLUE (-2900 5050);
FORCEPROP 2 LASTPIN (-2950 1700) $PN 146
J 2
(-2960 1710);
DISPLAY 0.617021 (-2960 1710);
PAINT ORANGE (-2960 1710);
FORCEPROP 2 LASTPIN (-2950 2050) $PN 284
J 2
(-2960 2060);
DISPLAY 0.617021 (-2960 2060);
PAINT ORANGE (-2960 2060);
FORCEPROP 2 LASTPIN (-2950 1850) $PN 285
J 2
(-2960 1860);
DISPLAY 0.617021 (-2960 1860);
PAINT ORANGE (-2960 1860);
FORCEPROP 2 LASTPIN (-2950 1800) $PN 141
J 2
(-2960 1810);
DISPLAY 0.617021 (-2960 1810);
PAINT ORANGE (-2960 1810);
FORCEPROP 2 LASTPIN (-2950 1400) $PN 230
J 2
(-2960 1410);
DISPLAY 0.617021 (-2960 1410);
PAINT ORANGE (-2960 1410);
FORCEPROP 2 LASTPIN (-2950 2000) $PN 238
J 2
(-2960 2010);
DISPLAY 0.617021 (-2960 2010);
PAINT ORANGE (-2960 2010);
FORCEPROP 2 LASTPIN (-2950 1950) $PN 140
J 2
(-2960 1960);
DISPLAY 0.617021 (-2960 1960);
PAINT ORANGE (-2960 1960);
FORCEPROP 2 LASTPIN (-2950 1900) $PN 139
J 2
(-2960 1910);
DISPLAY 0.617021 (-2960 1910);
PAINT ORANGE (-2960 1910);
FORCEPROP 2 LASTPIN (-2950 3350) $PN 237
J 2
(-2960 3360);
DISPLAY 0.617021 (-2960 3360);
PAINT ORANGE (-2960 3360);
FORCEPROP 2 LASTPIN (-2950 3300) $PN 93
J 2
(-2960 3310);
DISPLAY 0.617021 (-2960 3310);
PAINT ORANGE (-2960 3310);
FORCEPROP 2 LASTPIN (-2950 3250) $PN 89
J 2
(-2960 3260);
DISPLAY 0.617021 (-2960 3260);
PAINT ORANGE (-2960 3260);
FORCEPROP 2 LASTPIN (-2950 3200) $PN 84
J 2
(-2960 3210);
DISPLAY 0.617021 (-2960 3210);
PAINT ORANGE (-2960 3210);
FORCEPROP 2 LASTPIN (-2950 1600) $PN 144
J 2
(-2960 1610);
DISPLAY 0.617021 (-2960 1610);
PAINT ORANGE (-2960 1610);
FORCEPROP 2 LASTPIN (-2950 1550) $PN 227
J 2
(-2960 1560);
DISPLAY 0.617021 (-2960 1560);
PAINT ORANGE (-2960 1560);
FORCEPROP 2 LASTPIN (-2950 1500) $PN 205
J 2
(-2960 1510);
DISPLAY 0.617021 (-2960 1510);
PAINT ORANGE (-2960 1510);
FORCEPROP 2 LASTPIN (-2950 2300) $PN 58
J 2
(-2960 2310);
DISPLAY 0.617021 (-2960 2310);
PAINT ORANGE (-2960 2310);
FORCEPROP 2 LASTPIN (-2950 2350) $PN 222
J 2
(-2960 2360);
DISPLAY 0.617021 (-2960 2360);
PAINT ORANGE (-2960 2360);
FORCEPROP 2 LASTPIN (-2950 2950) $PN 91
J 2
(-2960 2960);
DISPLAY 0.617021 (-2960 2960);
PAINT ORANGE (-2960 2960);
FORCEPROP 2 LASTPIN (-2950 2900) $PN 87
J 2
(-2960 2910);
DISPLAY 0.617021 (-2960 2910);
PAINT ORANGE (-2960 2910);
FORCEPROP 2 LASTPIN (-2950 2250) $PN 78
J 2
(-2960 2260);
DISPLAY 0.617021 (-2960 2260);
PAINT ORANGE (-2960 2260);
FORCEPROP 2 LASTPIN (-1950 4850) $PN 280
J 0
(-1940 4860);
DISPLAY 0.617021 (-1940 4860);
PAINT ORANGE (-1940 4860);
FORCEPROP 2 LASTPIN (-1950 4800) $PN 135
J 0
(-1940 4810);
DISPLAY 0.617021 (-1940 4810);
PAINT ORANGE (-1940 4810);
FORCEPROP 2 LASTPIN (-1950 4750) $PN 273
J 0
(-1940 4760);
DISPLAY 0.617021 (-1940 4760);
PAINT ORANGE (-1940 4760);
FORCEPROP 2 LASTPIN (-1950 4700) $PN 128
J 0
(-1940 4710);
DISPLAY 0.617021 (-1940 4710);
PAINT ORANGE (-1940 4710);
FORCEPROP 2 LASTPIN (-1950 4650) $PN 282
J 0
(-1940 4660);
DISPLAY 0.617021 (-1940 4660);
PAINT ORANGE (-1940 4660);
FORCEPROP 2 LASTPIN (-1950 4600) $PN 137
J 0
(-1940 4610);
DISPLAY 0.617021 (-1940 4610);
PAINT ORANGE (-1940 4610);
FORCEPROP 2 LASTPIN (-1950 4550) $PN 275
J 0
(-1940 4560);
DISPLAY 0.617021 (-1940 4560);
PAINT ORANGE (-1940 4560);
FORCEPROP 2 LASTPIN (-1950 4500) $PN 130
J 0
(-1940 4510);
DISPLAY 0.617021 (-1940 4510);
PAINT ORANGE (-1940 4510);
FORCEPROP 2 LASTPIN (-1950 4450) $PN 269
J 0
(-1940 4460);
DISPLAY 0.617021 (-1940 4460);
PAINT ORANGE (-1940 4460);
FORCEPROP 2 LASTPIN (-1950 4400) $PN 124
J 0
(-1940 4410);
DISPLAY 0.617021 (-1940 4410);
PAINT ORANGE (-1940 4410);
FORCEPROP 2 LASTPIN (-1950 4350) $PN 262
J 0
(-1940 4360);
DISPLAY 0.617021 (-1940 4360);
PAINT ORANGE (-1940 4360);
FORCEPROP 2 LASTPIN (-1950 4300) $PN 117
J 0
(-1940 4310);
DISPLAY 0.617021 (-1940 4310);
PAINT ORANGE (-1940 4310);
FORCEPROP 2 LASTPIN (-1950 4250) $PN 271
J 0
(-1940 4260);
DISPLAY 0.617021 (-1940 4260);
PAINT ORANGE (-1940 4260);
FORCEPROP 2 LASTPIN (-1950 4200) $PN 126
J 0
(-1940 4210);
DISPLAY 0.617021 (-1940 4210);
PAINT ORANGE (-1940 4210);
FORCEPROP 2 LASTPIN (-1950 4150) $PN 264
J 0
(-1940 4160);
DISPLAY 0.617021 (-1940 4160);
PAINT ORANGE (-1940 4160);
FORCEPROP 2 LASTPIN (-1950 4100) $PN 119
J 0
(-1940 4110);
DISPLAY 0.617021 (-1940 4110);
PAINT ORANGE (-1940 4110);
FORCEPROP 2 LASTPIN (-1950 4050) $PN 258
J 0
(-1940 4060);
DISPLAY 0.617021 (-1940 4060);
PAINT ORANGE (-1940 4060);
FORCEPROP 2 LASTPIN (-1950 4000) $PN 113
J 0
(-1940 4010);
DISPLAY 0.617021 (-1940 4010);
PAINT ORANGE (-1940 4010);
FORCEPROP 2 LASTPIN (-1950 3950) $PN 251
J 0
(-1940 3960);
DISPLAY 0.617021 (-1940 3960);
PAINT ORANGE (-1940 3960);
FORCEPROP 2 LASTPIN (-1950 3900) $PN 106
J 0
(-1940 3910);
DISPLAY 0.617021 (-1940 3910);
PAINT ORANGE (-1940 3910);
FORCEPROP 2 LASTPIN (-1950 3850) $PN 260
J 0
(-1940 3860);
DISPLAY 0.617021 (-1940 3860);
PAINT ORANGE (-1940 3860);
FORCEPROP 2 LASTPIN (-1950 3800) $PN 115
J 0
(-1940 3810);
DISPLAY 0.617021 (-1940 3810);
PAINT ORANGE (-1940 3810);
FORCEPROP 2 LASTPIN (-1950 3750) $PN 253
J 0
(-1940 3760);
DISPLAY 0.617021 (-1940 3760);
PAINT ORANGE (-1940 3760);
FORCEPROP 2 LASTPIN (-1950 3700) $PN 108
J 0
(-1940 3710);
DISPLAY 0.617021 (-1940 3710);
PAINT ORANGE (-1940 3710);
FORCEPROP 2 LASTPIN (-1950 3650) $PN 247
J 0
(-1940 3660);
DISPLAY 0.617021 (-1940 3660);
PAINT ORANGE (-1940 3660);
FORCEPROP 2 LASTPIN (-1950 3600) $PN 102
J 0
(-1940 3610);
DISPLAY 0.617021 (-1940 3610);
PAINT ORANGE (-1940 3610);
FORCEPROP 2 LASTPIN (-1950 3550) $PN 240
J 0
(-1940 3560);
DISPLAY 0.617021 (-1940 3560);
PAINT ORANGE (-1940 3560);
FORCEPROP 2 LASTPIN (-1950 3500) $PN 95
J 0
(-1940 3510);
DISPLAY 0.617021 (-1940 3510);
PAINT ORANGE (-1940 3510);
FORCEPROP 2 LASTPIN (-1950 3450) $PN 249
J 0
(-1940 3460);
DISPLAY 0.617021 (-1940 3460);
PAINT ORANGE (-1940 3460);
FORCEPROP 2 LASTPIN (-1950 3400) $PN 104
J 0
(-1940 3410);
DISPLAY 0.617021 (-1940 3410);
PAINT ORANGE (-1940 3410);
FORCEPROP 2 LASTPIN (-1950 3350) $PN 242
J 0
(-1940 3360);
DISPLAY 0.617021 (-1940 3360);
PAINT ORANGE (-1940 3360);
FORCEPROP 2 LASTPIN (-1950 3300) $PN 97
J 0
(-1940 3310);
DISPLAY 0.617021 (-1940 3310);
PAINT ORANGE (-1940 3310);
FORCEPROP 2 LASTPIN (-1950 3250) $PN 188
J 0
(-1940 3260);
DISPLAY 0.617021 (-1940 3260);
PAINT ORANGE (-1940 3260);
FORCEPROP 2 LASTPIN (-1950 3200) $PN 43
J 0
(-1940 3210);
DISPLAY 0.617021 (-1940 3210);
PAINT ORANGE (-1940 3210);
FORCEPROP 2 LASTPIN (-1950 3150) $PN 181
J 0
(-1940 3160);
DISPLAY 0.617021 (-1940 3160);
PAINT ORANGE (-1940 3160);
FORCEPROP 2 LASTPIN (-1950 3100) $PN 36
J 0
(-1940 3110);
DISPLAY 0.617021 (-1940 3110);
PAINT ORANGE (-1940 3110);
FORCEPROP 2 LASTPIN (-1950 3050) $PN 190
J 0
(-1940 3060);
DISPLAY 0.617021 (-1940 3060);
PAINT ORANGE (-1940 3060);
FORCEPROP 2 LASTPIN (-1950 3000) $PN 45
J 0
(-1940 3010);
DISPLAY 0.617021 (-1940 3010);
PAINT ORANGE (-1940 3010);
FORCEPROP 2 LASTPIN (-1950 2950) $PN 183
J 0
(-1940 2960);
DISPLAY 0.617021 (-1940 2960);
PAINT ORANGE (-1940 2960);
FORCEPROP 2 LASTPIN (-1950 2900) $PN 38
J 0
(-1940 2910);
DISPLAY 0.617021 (-1940 2910);
PAINT ORANGE (-1940 2910);
FORCEPROP 2 LASTPIN (-1950 2850) $PN 177
J 0
(-1940 2860);
DISPLAY 0.617021 (-1940 2860);
PAINT ORANGE (-1940 2860);
FORCEPROP 2 LASTPIN (-1950 2800) $PN 32
J 0
(-1940 2810);
DISPLAY 0.617021 (-1940 2810);
PAINT ORANGE (-1940 2810);
FORCEPROP 2 LASTPIN (-1950 2750) $PN 170
J 0
(-1940 2760);
DISPLAY 0.617021 (-1940 2760);
PAINT ORANGE (-1940 2760);
FORCEPROP 2 LASTPIN (-1950 2700) $PN 25
J 0
(-1940 2710);
DISPLAY 0.617021 (-1940 2710);
PAINT ORANGE (-1940 2710);
FORCEPROP 2 LASTPIN (-1950 2650) $PN 179
J 0
(-1940 2660);
DISPLAY 0.617021 (-1940 2660);
PAINT ORANGE (-1940 2660);
FORCEPROP 2 LASTPIN (-1950 2600) $PN 34
J 0
(-1940 2610);
DISPLAY 0.617021 (-1940 2610);
PAINT ORANGE (-1940 2610);
FORCEPROP 2 LASTPIN (-1950 2550) $PN 172
J 0
(-1940 2560);
DISPLAY 0.617021 (-1940 2560);
PAINT ORANGE (-1940 2560);
FORCEPROP 2 LASTPIN (-1950 2500) $PN 27
J 0
(-1940 2510);
DISPLAY 0.617021 (-1940 2510);
PAINT ORANGE (-1940 2510);
FORCEPROP 2 LASTPIN (-1950 2450) $PN 166
J 0
(-1940 2460);
DISPLAY 0.617021 (-1940 2460);
PAINT ORANGE (-1940 2460);
FORCEPROP 2 LASTPIN (-1950 2400) $PN 21
J 0
(-1940 2410);
DISPLAY 0.617021 (-1940 2410);
PAINT ORANGE (-1940 2410);
FORCEPROP 2 LASTPIN (-1950 2350) $PN 159
J 0
(-1940 2360);
DISPLAY 0.617021 (-1940 2360);
PAINT ORANGE (-1940 2360);
FORCEPROP 2 LASTPIN (-1950 2300) $PN 14
J 0
(-1940 2310);
DISPLAY 0.617021 (-1940 2310);
PAINT ORANGE (-1940 2310);
FORCEPROP 2 LASTPIN (-1950 2250) $PN 168
J 0
(-1940 2260);
DISPLAY 0.617021 (-1940 2260);
PAINT ORANGE (-1940 2260);
FORCEPROP 2 LASTPIN (-1950 2200) $PN 23
J 0
(-1940 2210);
DISPLAY 0.617021 (-1940 2210);
PAINT ORANGE (-1940 2210);
FORCEPROP 2 LASTPIN (-1950 2150) $PN 161
J 0
(-1940 2160);
DISPLAY 0.617021 (-1940 2160);
PAINT ORANGE (-1940 2160);
FORCEPROP 2 LASTPIN (-1950 2100) $PN 16
J 0
(-1940 2110);
DISPLAY 0.617021 (-1940 2110);
PAINT ORANGE (-1940 2110);
FORCEPROP 2 LASTPIN (-1950 2050) $PN 155
J 0
(-1940 2060);
DISPLAY 0.617021 (-1940 2060);
PAINT ORANGE (-1940 2060);
FORCEPROP 2 LASTPIN (-1950 2000) $PN 10
J 0
(-1940 2010);
DISPLAY 0.617021 (-1940 2010);
PAINT ORANGE (-1940 2010);
FORCEPROP 2 LASTPIN (-1950 1950) $PN 148
J 0
(-1940 1960);
DISPLAY 0.617021 (-1940 1960);
PAINT ORANGE (-1940 1960);
FORCEPROP 2 LASTPIN (-1950 1900) $PN 3
J 0
(-1940 1910);
DISPLAY 0.617021 (-1940 1910);
PAINT ORANGE (-1940 1910);
FORCEPROP 2 LASTPIN (-1950 1850) $PN 157
J 0
(-1940 1860);
DISPLAY 0.617021 (-1940 1860);
PAINT ORANGE (-1940 1860);
FORCEPROP 2 LASTPIN (-1950 1800) $PN 12
J 0
(-1940 1810);
DISPLAY 0.617021 (-1940 1810);
PAINT ORANGE (-1940 1810);
FORCEPROP 2 LASTPIN (-1950 1750) $PN 150
J 0
(-1940 1760);
DISPLAY 0.617021 (-1940 1760);
PAINT ORANGE (-1940 1760);
FORCEPROP 2 LASTPIN (-1950 1700) $PN 5
J 0
(-1940 1710);
DISPLAY 0.617021 (-1940 1710);
PAINT ORANGE (-1940 1710);
FORCEPROP 2 LASTPIN (-2950 3100) $PN 203
J 2
(-2960 3110);
DISPLAY 0.617021 (-2960 3110);
PAINT ORANGE (-2960 3110);
FORCEPROP 2 LASTPIN (-2950 3050) $PN 60
J 2
(-2960 3060);
DISPLAY 0.617021 (-2960 3060);
PAINT ORANGE (-2960 3060);
FORCEPROP 2 LASTPIN (-2950 3650) $PN 218
J 2
(-2960 3660);
DISPLAY 0.617021 (-2960 3660);
PAINT ORANGE (-2960 3660);
FORCEPROP 2 LASTPIN (-2950 3600) $PN 219
J 2
(-2960 3610);
DISPLAY 0.617021 (-2960 3610);
PAINT ORANGE (-2960 3610);
FORCEPROP 2 LASTPIN (-2950 3550) $PN 74
J 2
(-2960 3560);
DISPLAY 0.617021 (-2960 3560);
PAINT ORANGE (-2960 3560);
FORCEPROP 2 LASTPIN (-2950 3500) $PN 75
J 2
(-2960 3510);
DISPLAY 0.617021 (-2960 3510);
PAINT ORANGE (-2960 3510);
FORCEPROP 2 LASTPIN (-2950 2800) $PN 199
J 2
(-2960 2810);
DISPLAY 0.617021 (-2960 2810);
PAINT ORANGE (-2960 2810);
FORCEPROP 2 LASTPIN (-2950 2750) $PN 54
J 2
(-2960 2760);
DISPLAY 0.617021 (-2960 2760);
PAINT ORANGE (-2960 2760);
FORCEPROP 2 LASTPIN (-2950 2700) $PN 192
J 2
(-2960 2710);
DISPLAY 0.617021 (-2960 2710);
PAINT ORANGE (-2960 2710);
FORCEPROP 2 LASTPIN (-2950 2650) $PN 47
J 2
(-2960 2660);
DISPLAY 0.617021 (-2960 2660);
PAINT ORANGE (-2960 2660);
FORCEPROP 2 LASTPIN (-2950 2600) $PN 201
J 2
(-2960 2610);
DISPLAY 0.617021 (-2960 2610);
PAINT ORANGE (-2960 2610);
FORCEPROP 2 LASTPIN (-2950 2550) $PN 56
J 2
(-2960 2560);
DISPLAY 0.617021 (-2960 2560);
PAINT ORANGE (-2960 2560);
FORCEPROP 2 LASTPIN (-2950 2500) $PN 194
J 2
(-2960 2510);
DISPLAY 0.617021 (-2960 2510);
PAINT ORANGE (-2960 2510);
FORCEPROP 2 LASTPIN (-2950 2450) $PN 49
J 2
(-2960 2460);
DISPLAY 0.617021 (-2960 2460);
PAINT ORANGE (-2960 2460);
FORCEPROP 2 LASTPIN (-2950 3400) $PN 235
J 2
(-2960 3410);
DISPLAY 0.617021 (-2960 3410);
PAINT ORANGE (-2960 3410);
FORCEPROP 2 LASTPIN (-2950 3800) $PN 207
J 2
(-2960 3810);
DISPLAY 0.617021 (-2960 3810);
PAINT ORANGE (-2960 3810);
FORCEPROP 2 LASTPIN (-2950 3750) $PN 63
J 2
(-2960 3760);
DISPLAY 0.617021 (-2960 3760);
PAINT ORANGE (-2960 3760);
FORCEPROP 2 LASTPIN (-2950 3900) $PN 224
J 2
(-2960 3910);
DISPLAY 0.617021 (-2960 3910);
PAINT ORANGE (-2960 3910);
FORCEPROP 2 LASTPIN (-2950 3850) $PN 81
J 2
(-2960 3860);
DISPLAY 0.617021 (-2960 3860);
PAINT ORANGE (-2960 3860);
FORCEPROP 2 LASTPIN (-2950 2200) $PN 208
J 2
(-2960 2210);
DISPLAY 0.617021 (-2960 2210);
PAINT ORANGE (-2960 2210);
FORCEPROP 2 LASTPIN (-2950 2150) $PN 62
J 2
(-2960 2160);
DISPLAY 0.617021 (-2960 2160);
PAINT ORANGE (-2960 2160);
FORCEPROP 2 LASTPIN (-2950 4850) $PN 234
J 2
(-2960 4860);
DISPLAY 0.617021 (-2960 4860);
PAINT ORANGE (-2960 4860);
FORCEPROP 2 LASTPIN (-2950 4800) $PN 82
J 2
(-2960 4810);
DISPLAY 0.617021 (-2960 4810);
PAINT ORANGE (-2960 4810);
FORCEPROP 2 LASTPIN (-2950 4750) $PN 86
J 2
(-2960 4760);
DISPLAY 0.617021 (-2960 4760);
PAINT ORANGE (-2960 4760);
FORCEPROP 2 LASTPIN (-2950 4700) $PN 228
J 2
(-2960 4710);
DISPLAY 0.617021 (-2960 4710);
PAINT ORANGE (-2960 4710);
FORCEPROP 2 LASTPIN (-2950 4650) $PN 232
J 2
(-2960 4660);
DISPLAY 0.617021 (-2960 4660);
PAINT ORANGE (-2960 4660);
FORCEPROP 2 LASTPIN (-2950 4600) $PN 65
J 2
(-2960 4610);
DISPLAY 0.617021 (-2960 4610);
PAINT ORANGE (-2960 4610);
FORCEPROP 2 LASTPIN (-2950 4550) $PN 210
J 2
(-2960 4560);
DISPLAY 0.617021 (-2960 4560);
PAINT ORANGE (-2960 4560);
FORCEPROP 2 LASTPIN (-2950 4500) $PN 225
J 2
(-2960 4510);
DISPLAY 0.617021 (-2960 4510);
PAINT ORANGE (-2960 4510);
FORCEPROP 2 LASTPIN (-2950 4450) $PN 66
J 2
(-2960 4460);
DISPLAY 0.617021 (-2960 4460);
PAINT ORANGE (-2960 4460);
FORCEPROP 2 LASTPIN (-2950 4400) $PN 68
J 2
(-2960 4410);
DISPLAY 0.617021 (-2960 4410);
PAINT ORANGE (-2960 4410);
FORCEPROP 2 LASTPIN (-2950 4350) $PN 211
J 2
(-2960 4360);
DISPLAY 0.617021 (-2960 4360);
PAINT ORANGE (-2960 4360);
FORCEPROP 2 LASTPIN (-2950 4300) $PN 69
J 2
(-2960 4310);
DISPLAY 0.617021 (-2960 4310);
PAINT ORANGE (-2960 4310);
FORCEPROP 2 LASTPIN (-2950 4250) $PN 213
J 2
(-2960 4260);
DISPLAY 0.617021 (-2960 4260);
PAINT ORANGE (-2960 4260);
FORCEPROP 2 LASTPIN (-2950 4200) $PN 214
J 2
(-2960 4210);
DISPLAY 0.617021 (-2960 4210);
PAINT ORANGE (-2960 4210);
FORCEPROP 2 LASTPIN (-2950 4150) $PN 71
J 2
(-2960 4160);
DISPLAY 0.617021 (-2960 4160);
PAINT ORANGE (-2960 4160);
FORCEPROP 2 LASTPIN (-2950 4100) $PN 216
J 2
(-2960 4110);
DISPLAY 0.617021 (-2960 4110);
PAINT ORANGE (-2960 4110);
FORCEPROP 2 LASTPIN (-2950 4050) $PN 72
J 2
(-2960 4060);
DISPLAY 0.617021 (-2960 4060);
PAINT ORANGE (-2960 4060);
FORCEPROP 2 LASTPIN (-2950 4000) $PN 79
J 2
(-2960 4010);
DISPLAY 0.617021 (-2960 4010);
PAINT ORANGE (-2960 4010);
FORCEPROP 1 LAST PACK_TYPE PIP
J 0
(-2900 5150);
PAINT SKYBLUE (-2900 5150);
DISPLAY INVISIBLE (-2900 5150);
FORCEPROP 2 LAST BOM_COST MEM
J 0
(-2450 3200);
PAINT ORANGE (-2450 3200);
DISPLAY INVISIBLE (-2450 3200);
FORCEPROP 2 LAST CDS_LIB mstr_sconn
J 0
(-2450 3200);
PAINT ORANGE (-2450 3200);
DISPLAY INVISIBLE (-2450 3200);
FORCEPROP 2 LAST SEC_TYPE PIP
J 0
(-2900 5150);
DISPLAY 1.021277 (-2900 5150);
PAINT ORANGE (-2900 5150);
DISPLAY INVISIBLE (-2900 5150);
FORCEPROP 2 LAST SEC 1
J 0
(-2900 5150);
DISPLAY 0.680851 (-2900 5150);
PAINT MONO (-2900 5150);
DISPLAY INVISIBLE (-2900 5150);
FORCEPROP 2 LAST CDS_LOCATION J1B1
J 0
(-2900 5100);
DISPLAY 0.617021 (-2900 5100);
PAINT AQUA (-2900 5100);
DISPLAY INVISIBLE (-2900 5100);
FORCEPROP 1 LAST PATH I111
J 0
(-2450 5050);
PAINT GREEN (-2450 5050);
DISPLAY INVISIBLE (-2450 5050);
FORCEPROP 2 LAST ROOM DDR4_CH_K
J 0
(-2450 3200);
PAINT ORANGE (-2450 3200);
DISPLAY INVISIBLE (-2450 3200);
FORCEADD TAP..6
(-3200 4800);
FORCEPROP 3 LASTPIN (-3150 4800) SIG_NAME M_K_MA<16>
J 0
(-3140 4810);
DISPLAY 0.659574 (-3140 4810);
PAINT MONO (-3140 4810);
DISPLAY INVISIBLE (-3140 4810);
FORCEPROP 1 LASTPIN (-3150 4800) BN 16
J 0
(-3200 4810);
DISPLAY 0.617021 (-3200 4810);
PAINT PINK (-3200 4810);
FORCEPROP 2 LAST CDS_LIB mstr_standard
J 2
(-3200 4800);
DISPLAY 0.787234 (-3200 4800);
PAINT MONO (-3200 4800);
DISPLAY INVISIBLE (-3200 4800);
FORCEPROP 1 LAST BODY_TYPE PLUMBING
J 0
(-3200 4750);
DISPLAY 1.234043 (-3200 4750);
PAINT GREEN (-3200 4750);
DISPLAY INVISIBLE (-3200 4750);
FORCEPROP 1 LAST HDL_TAP TRUE
J 0
(-2875 4675);
DISPLAY 1.234043 (-2875 4675);
PAINT GREEN (-2875 4675);
DISPLAY INVISIBLE (-2875 4675);
FORCEPROP 1 LAST PATH I112
J 0
(-3200 4800);
DISPLAY 0.936170 (-3200 4800);
PAINT GREEN (-3200 4800);
DISPLAY INVISIBLE (-3200 4800);
FORCEADD TAP..6
(-3200 4850);
FORCEPROP 3 LASTPIN (-3150 4850) SIG_NAME M_K_MA<17>
J 0
(-3140 4860);
DISPLAY 0.659574 (-3140 4860);
PAINT MONO (-3140 4860);
DISPLAY INVISIBLE (-3140 4860);
FORCEPROP 1 LASTPIN (-3150 4850) BN 17
J 0
(-3200 4860);
DISPLAY 0.617021 (-3200 4860);
PAINT PINK (-3200 4860);
FORCEPROP 2 LAST CDS_LIB mstr_standard
J 0
(-3200 4850);
DISPLAY 0.787234 (-3200 4850);
PAINT MONO (-3200 4850);
DISPLAY INVISIBLE (-3200 4850);
FORCEPROP 1 LAST BODY_TYPE PLUMBING
J 0
(-3200 4800);
DISPLAY 1.234043 (-3200 4800);
PAINT GREEN (-3200 4800);
DISPLAY INVISIBLE (-3200 4800);
FORCEPROP 1 LAST HDL_TAP TRUE
J 0
(-2875 4725);
DISPLAY 1.234043 (-2875 4725);
PAINT GREEN (-2875 4725);
DISPLAY INVISIBLE (-2875 4725);
FORCEPROP 1 LAST PATH I113
J 0
(-3200 4850);
DISPLAY 0.936170 (-3200 4850);
PAINT GREEN (-3200 4850);
DISPLAY INVISIBLE (-3200 4850);
FORCEADD TAP..6
(-3200 4750);
FORCEPROP 3 LASTPIN (-3150 4750) SIG_NAME M_K_MA<15>
J 0
(-3140 4760);
DISPLAY 0.659574 (-3140 4760);
PAINT MONO (-3140 4760);
DISPLAY INVISIBLE (-3140 4760);
FORCEPROP 1 LASTPIN (-3150 4750) BN 15
J 0
(-3200 4760);
DISPLAY 0.617021 (-3200 4760);
PAINT PINK (-3200 4760);
FORCEPROP 2 LAST CDS_LIB mstr_standard
J 2
(-3200 4750);
DISPLAY 0.787234 (-3200 4750);
PAINT MONO (-3200 4750);
DISPLAY INVISIBLE (-3200 4750);
FORCEPROP 1 LAST BODY_TYPE PLUMBING
J 0
(-3200 4700);
DISPLAY 1.234043 (-3200 4700);
PAINT GREEN (-3200 4700);
DISPLAY INVISIBLE (-3200 4700);
FORCEPROP 1 LAST HDL_TAP TRUE
J 0
(-2875 4625);
DISPLAY 1.234043 (-2875 4625);
PAINT GREEN (-2875 4625);
DISPLAY INVISIBLE (-2875 4625);
FORCEPROP 1 LAST PATH I114
J 0
(-3200 4750);
DISPLAY 0.936170 (-3200 4750);
PAINT GREEN (-3200 4750);
DISPLAY INVISIBLE (-3200 4750);
FORCEADD TAP..6
(-3200 4700);
FORCEPROP 3 LASTPIN (-3150 4700) SIG_NAME M_K_MA<14>
J 0
(-3140 4710);
DISPLAY 0.659574 (-3140 4710);
PAINT MONO (-3140 4710);
DISPLAY INVISIBLE (-3140 4710);
FORCEPROP 1 LASTPIN (-3150 4700) BN 14
J 0
(-3200 4710);
DISPLAY 0.617021 (-3200 4710);
PAINT PINK (-3200 4710);
FORCEPROP 2 LAST CDS_LIB mstr_standard
J 2
(-3200 4700);
DISPLAY 0.787234 (-3200 4700);
PAINT MONO (-3200 4700);
DISPLAY INVISIBLE (-3200 4700);
FORCEPROP 1 LAST BODY_TYPE PLUMBING
J 0
(-3200 4650);
DISPLAY 1.234043 (-3200 4650);
PAINT GREEN (-3200 4650);
DISPLAY INVISIBLE (-3200 4650);
FORCEPROP 1 LAST HDL_TAP TRUE
J 0
(-2875 4575);
DISPLAY 1.234043 (-2875 4575);
PAINT GREEN (-2875 4575);
DISPLAY INVISIBLE (-2875 4575);
FORCEPROP 1 LAST PATH I115
J 0
(-3200 4700);
DISPLAY 0.936170 (-3200 4700);
PAINT GREEN (-3200 4700);
DISPLAY INVISIBLE (-3200 4700);
FORCEADD TAP..6
(-3200 4650);
FORCEPROP 3 LASTPIN (-3150 4650) SIG_NAME M_K_MA<13>
J 0
(-3140 4660);
DISPLAY 0.659574 (-3140 4660);
PAINT MONO (-3140 4660);
DISPLAY INVISIBLE (-3140 4660);
FORCEPROP 1 LASTPIN (-3150 4650) BN 13
J 0
(-3200 4660);
DISPLAY 0.617021 (-3200 4660);
PAINT PINK (-3200 4660);
FORCEPROP 2 LAST CDS_LIB mstr_standard
J 2
(-3200 4650);
DISPLAY 0.787234 (-3200 4650);
PAINT MONO (-3200 4650);
DISPLAY INVISIBLE (-3200 4650);
FORCEPROP 1 LAST BODY_TYPE PLUMBING
J 0
(-3200 4600);
DISPLAY 1.234043 (-3200 4600);
PAINT GREEN (-3200 4600);
DISPLAY INVISIBLE (-3200 4600);
FORCEPROP 1 LAST HDL_TAP TRUE
J 0
(-2875 4525);
DISPLAY 1.234043 (-2875 4525);
PAINT GREEN (-2875 4525);
DISPLAY INVISIBLE (-2875 4525);
FORCEPROP 1 LAST PATH I116
J 0
(-3200 4650);
DISPLAY 0.936170 (-3200 4650);
PAINT GREEN (-3200 4650);
DISPLAY INVISIBLE (-3200 4650);
FORCEADD TAP..6
(-3200 4600);
FORCEPROP 3 LASTPIN (-3150 4600) SIG_NAME M_K_MA<12>
J 0
(-3140 4610);
DISPLAY 0.659574 (-3140 4610);
PAINT MONO (-3140 4610);
DISPLAY INVISIBLE (-3140 4610);
FORCEPROP 1 LASTPIN (-3150 4600) BN 12
J 0
(-3200 4610);
DISPLAY 0.617021 (-3200 4610);
PAINT PINK (-3200 4610);
FORCEPROP 2 LAST CDS_LIB mstr_standard
J 2
(-3200 4600);
DISPLAY 0.787234 (-3200 4600);
PAINT MONO (-3200 4600);
DISPLAY INVISIBLE (-3200 4600);
FORCEPROP 1 LAST BODY_TYPE PLUMBING
J 0
(-3200 4550);
DISPLAY 1.234043 (-3200 4550);
PAINT GREEN (-3200 4550);
DISPLAY INVISIBLE (-3200 4550);
FORCEPROP 1 LAST HDL_TAP TRUE
J 0
(-2875 4475);
DISPLAY 1.234043 (-2875 4475);
PAINT GREEN (-2875 4475);
DISPLAY INVISIBLE (-2875 4475);
FORCEPROP 1 LAST PATH I117
J 0
(-3200 4600);
DISPLAY 0.936170 (-3200 4600);
PAINT GREEN (-3200 4600);
DISPLAY INVISIBLE (-3200 4600);
FORCEADD TAP..6
(-3200 4550);
FORCEPROP 3 LASTPIN (-3150 4550) SIG_NAME M_K_MA<11>
J 0
(-3140 4560);
DISPLAY 0.659574 (-3140 4560);
PAINT MONO (-3140 4560);
DISPLAY INVISIBLE (-3140 4560);
FORCEPROP 1 LASTPIN (-3150 4550) BN 11
J 0
(-3200 4560);
DISPLAY 0.617021 (-3200 4560);
PAINT PINK (-3200 4560);
FORCEPROP 2 LAST CDS_LIB mstr_standard
J 2
(-3200 4550);
DISPLAY 0.787234 (-3200 4550);
PAINT MONO (-3200 4550);
DISPLAY INVISIBLE (-3200 4550);
FORCEPROP 1 LAST BODY_TYPE PLUMBING
J 0
(-3200 4500);
DISPLAY 1.234043 (-3200 4500);
PAINT GREEN (-3200 4500);
DISPLAY INVISIBLE (-3200 4500);
FORCEPROP 1 LAST HDL_TAP TRUE
J 0
(-2875 4425);
DISPLAY 1.234043 (-2875 4425);
PAINT GREEN (-2875 4425);
DISPLAY INVISIBLE (-2875 4425);
FORCEPROP 1 LAST PATH I118
J 0
(-3200 4550);
DISPLAY 0.936170 (-3200 4550);
PAINT GREEN (-3200 4550);
DISPLAY INVISIBLE (-3200 4550);
FORCEADD TAP..6
(-3200 4500);
FORCEPROP 3 LASTPIN (-3150 4500) SIG_NAME M_K_MA<10>
J 0
(-3140 4510);
DISPLAY 0.659574 (-3140 4510);
PAINT MONO (-3140 4510);
DISPLAY INVISIBLE (-3140 4510);
FORCEPROP 1 LASTPIN (-3150 4500) BN 10
J 0
(-3200 4510);
DISPLAY 0.617021 (-3200 4510);
PAINT PINK (-3200 4510);
FORCEPROP 2 LAST CDS_LIB mstr_standard
J 2
(-3200 4500);
DISPLAY 0.787234 (-3200 4500);
PAINT MONO (-3200 4500);
DISPLAY INVISIBLE (-3200 4500);
FORCEPROP 1 LAST BODY_TYPE PLUMBING
J 0
(-3200 4450);
DISPLAY 1.234043 (-3200 4450);
PAINT GREEN (-3200 4450);
DISPLAY INVISIBLE (-3200 4450);
FORCEPROP 1 LAST HDL_TAP TRUE
J 0
(-2875 4375);
DISPLAY 1.234043 (-2875 4375);
PAINT GREEN (-2875 4375);
DISPLAY INVISIBLE (-2875 4375);
FORCEPROP 1 LAST PATH I119
J 0
(-3200 4500);
DISPLAY 0.936170 (-3200 4500);
PAINT GREEN (-3200 4500);
DISPLAY INVISIBLE (-3200 4500);
FORCEADD TAP..6
R 2
(700 5100);
FORCEPROP 3 LASTPIN (650 5100) SIG_NAME M_K_DQS_DP<16>
J 0
(660 5110);
DISPLAY 0.659574 (660 5110);
PAINT MONO (660 5110);
DISPLAY INVISIBLE (660 5110);
FORCEPROP 1 LASTPIN (650 5100) BN 16
J 2
(700 5110);
DISPLAY 0.617021 (700 5110);
PAINT PINK (700 5110);
FORCEPROP 2 LAST CDS_LIB mstr_standard
J 0
(700 5100);
DISPLAY 0.787234 (700 5100);
PAINT MONO (700 5100);
DISPLAY INVISIBLE (700 5100);
FORCEPROP 1 LAST BODY_TYPE PLUMBING
J 2
(700 5050);
DISPLAY 1.234043 (700 5050);
PAINT GREEN (700 5050);
DISPLAY INVISIBLE (700 5050);
FORCEPROP 1 LAST HDL_TAP TRUE
J 2
(375 4975);
DISPLAY 1.234043 (375 4975);
PAINT GREEN (375 4975);
DISPLAY INVISIBLE (375 4975);
FORCEPROP 1 LAST PATH I12
J 2
(700 5100);
DISPLAY 0.936170 (700 5100);
PAINT GREEN (700 5100);
DISPLAY INVISIBLE (700 5100);
FORCEADD TAP..6
(-3200 4450);
FORCEPROP 3 LASTPIN (-3150 4450) SIG_NAME M_K_MA<9>
J 0
(-3140 4460);
DISPLAY 0.659574 (-3140 4460);
PAINT MONO (-3140 4460);
DISPLAY INVISIBLE (-3140 4460);
FORCEPROP 1 LASTPIN (-3150 4450) BN 9
J 0
(-3200 4460);
DISPLAY 0.617021 (-3200 4460);
PAINT PINK (-3200 4460);
FORCEPROP 2 LAST CDS_LIB mstr_standard
J 2
(-3200 4450);
DISPLAY 0.787234 (-3200 4450);
PAINT MONO (-3200 4450);
DISPLAY INVISIBLE (-3200 4450);
FORCEPROP 1 LAST BODY_TYPE PLUMBING
J 0
(-3200 4400);
DISPLAY 1.234043 (-3200 4400);
PAINT GREEN (-3200 4400);
DISPLAY INVISIBLE (-3200 4400);
FORCEPROP 1 LAST HDL_TAP TRUE
J 0
(-2875 4325);
DISPLAY 1.234043 (-2875 4325);
PAINT GREEN (-2875 4325);
DISPLAY INVISIBLE (-2875 4325);
FORCEPROP 1 LAST PATH I120
J 0
(-3200 4450);
DISPLAY 0.936170 (-3200 4450);
PAINT GREEN (-3200 4450);
DISPLAY INVISIBLE (-3200 4450);
FORCEADD TAP..6
(-3200 4400);
FORCEPROP 3 LASTPIN (-3150 4400) SIG_NAME M_K_MA<8>
J 0
(-3140 4410);
DISPLAY 0.659574 (-3140 4410);
PAINT MONO (-3140 4410);
DISPLAY INVISIBLE (-3140 4410);
FORCEPROP 1 LASTPIN (-3150 4400) BN 8
J 0
(-3200 4410);
DISPLAY 0.617021 (-3200 4410);
PAINT PINK (-3200 4410);
FORCEPROP 2 LAST CDS_LIB mstr_standard
J 2
(-3200 4400);
DISPLAY 0.787234 (-3200 4400);
PAINT MONO (-3200 4400);
DISPLAY INVISIBLE (-3200 4400);
FORCEPROP 1 LAST BODY_TYPE PLUMBING
J 0
(-3200 4350);
DISPLAY 1.234043 (-3200 4350);
PAINT GREEN (-3200 4350);
DISPLAY INVISIBLE (-3200 4350);
FORCEPROP 1 LAST HDL_TAP TRUE
J 0
(-2875 4275);
DISPLAY 1.234043 (-2875 4275);
PAINT GREEN (-2875 4275);
DISPLAY INVISIBLE (-2875 4275);
FORCEPROP 1 LAST PATH I121
J 0
(-3200 4400);
DISPLAY 0.936170 (-3200 4400);
PAINT GREEN (-3200 4400);
DISPLAY INVISIBLE (-3200 4400);
FORCEADD TAP..6
(-3200 4350);
FORCEPROP 3 LASTPIN (-3150 4350) SIG_NAME M_K_MA<7>
J 0
(-3140 4360);
DISPLAY 0.659574 (-3140 4360);
PAINT MONO (-3140 4360);
DISPLAY INVISIBLE (-3140 4360);
FORCEPROP 1 LASTPIN (-3150 4350) BN 7
J 0
(-3200 4360);
DISPLAY 0.617021 (-3200 4360);
PAINT PINK (-3200 4360);
FORCEPROP 2 LAST CDS_LIB mstr_standard
J 2
(-3200 4350);
DISPLAY 0.787234 (-3200 4350);
PAINT MONO (-3200 4350);
DISPLAY INVISIBLE (-3200 4350);
FORCEPROP 1 LAST BODY_TYPE PLUMBING
J 0
(-3200 4300);
DISPLAY 1.234043 (-3200 4300);
PAINT GREEN (-3200 4300);
DISPLAY INVISIBLE (-3200 4300);
FORCEPROP 1 LAST HDL_TAP TRUE
J 0
(-2875 4225);
DISPLAY 1.234043 (-2875 4225);
PAINT GREEN (-2875 4225);
DISPLAY INVISIBLE (-2875 4225);
FORCEPROP 1 LAST PATH I122
J 0
(-3200 4350);
DISPLAY 0.936170 (-3200 4350);
PAINT GREEN (-3200 4350);
DISPLAY INVISIBLE (-3200 4350);
FORCEADD TAP..6
(-3200 4300);
FORCEPROP 3 LASTPIN (-3150 4300) SIG_NAME M_K_MA<6>
J 0
(-3140 4310);
DISPLAY 0.659574 (-3140 4310);
PAINT MONO (-3140 4310);
DISPLAY INVISIBLE (-3140 4310);
FORCEPROP 1 LASTPIN (-3150 4300) BN 6
J 0
(-3200 4310);
DISPLAY 0.617021 (-3200 4310);
PAINT PINK (-3200 4310);
FORCEPROP 2 LAST CDS_LIB mstr_standard
J 2
(-3200 4300);
DISPLAY 0.787234 (-3200 4300);
PAINT MONO (-3200 4300);
DISPLAY INVISIBLE (-3200 4300);
FORCEPROP 1 LAST BODY_TYPE PLUMBING
J 0
(-3200 4250);
DISPLAY 1.234043 (-3200 4250);
PAINT GREEN (-3200 4250);
DISPLAY INVISIBLE (-3200 4250);
FORCEPROP 1 LAST HDL_TAP TRUE
J 0
(-2875 4175);
DISPLAY 1.234043 (-2875 4175);
PAINT GREEN (-2875 4175);
DISPLAY INVISIBLE (-2875 4175);
FORCEPROP 1 LAST PATH I123
J 0
(-3200 4300);
DISPLAY 0.936170 (-3200 4300);
PAINT GREEN (-3200 4300);
DISPLAY INVISIBLE (-3200 4300);
FORCEADD TAP..6
(-3200 4250);
FORCEPROP 3 LASTPIN (-3150 4250) SIG_NAME M_K_MA<5>
J 0
(-3140 4260);
DISPLAY 0.659574 (-3140 4260);
PAINT MONO (-3140 4260);
DISPLAY INVISIBLE (-3140 4260);
FORCEPROP 1 LASTPIN (-3150 4250) BN 5
J 0
(-3200 4260);
DISPLAY 0.617021 (-3200 4260);
PAINT PINK (-3200 4260);
FORCEPROP 2 LAST CDS_LIB mstr_standard
J 2
(-3200 4250);
DISPLAY 0.787234 (-3200 4250);
PAINT MONO (-3200 4250);
DISPLAY INVISIBLE (-3200 4250);
FORCEPROP 1 LAST BODY_TYPE PLUMBING
J 0
(-3200 4200);
DISPLAY 1.234043 (-3200 4200);
PAINT GREEN (-3200 4200);
DISPLAY INVISIBLE (-3200 4200);
FORCEPROP 1 LAST HDL_TAP TRUE
J 0
(-2875 4125);
DISPLAY 1.234043 (-2875 4125);
PAINT GREEN (-2875 4125);
DISPLAY INVISIBLE (-2875 4125);
FORCEPROP 1 LAST PATH I124
J 0
(-3200 4250);
DISPLAY 0.936170 (-3200 4250);
PAINT GREEN (-3200 4250);
DISPLAY INVISIBLE (-3200 4250);
FORCEADD TAP..6
(-3200 4200);
FORCEPROP 3 LASTPIN (-3150 4200) SIG_NAME M_K_MA<4>
J 0
(-3140 4210);
DISPLAY 0.659574 (-3140 4210);
PAINT MONO (-3140 4210);
DISPLAY INVISIBLE (-3140 4210);
FORCEPROP 1 LASTPIN (-3150 4200) BN 4
J 0
(-3200 4210);
DISPLAY 0.617021 (-3200 4210);
PAINT PINK (-3200 4210);
FORCEPROP 2 LAST CDS_LIB mstr_standard
J 2
(-3200 4200);
DISPLAY 0.787234 (-3200 4200);
PAINT MONO (-3200 4200);
DISPLAY INVISIBLE (-3200 4200);
FORCEPROP 1 LAST BODY_TYPE PLUMBING
J 0
(-3200 4150);
DISPLAY 1.234043 (-3200 4150);
PAINT GREEN (-3200 4150);
DISPLAY INVISIBLE (-3200 4150);
FORCEPROP 1 LAST HDL_TAP TRUE
J 0
(-2875 4075);
DISPLAY 1.234043 (-2875 4075);
PAINT GREEN (-2875 4075);
DISPLAY INVISIBLE (-2875 4075);
FORCEPROP 1 LAST PATH I125
J 0
(-3200 4200);
DISPLAY 0.936170 (-3200 4200);
PAINT GREEN (-3200 4200);
DISPLAY INVISIBLE (-3200 4200);
FORCEADD TAP..6
(-3200 4100);
FORCEPROP 3 LASTPIN (-3150 4100) SIG_NAME M_K_MA<2>
J 0
(-3140 4110);
DISPLAY 0.659574 (-3140 4110);
PAINT MONO (-3140 4110);
DISPLAY INVISIBLE (-3140 4110);
FORCEPROP 1 LASTPIN (-3150 4100) BN 2
J 0
(-3200 4110);
DISPLAY 0.617021 (-3200 4110);
PAINT PINK (-3200 4110);
FORCEPROP 2 LAST CDS_LIB mstr_standard
J 2
(-3200 4100);
DISPLAY 0.787234 (-3200 4100);
PAINT MONO (-3200 4100);
DISPLAY INVISIBLE (-3200 4100);
FORCEPROP 1 LAST BODY_TYPE PLUMBING
J 0
(-3200 4050);
DISPLAY 1.234043 (-3200 4050);
PAINT GREEN (-3200 4050);
DISPLAY INVISIBLE (-3200 4050);
FORCEPROP 1 LAST HDL_TAP TRUE
J 0
(-2875 3975);
DISPLAY 1.234043 (-2875 3975);
PAINT GREEN (-2875 3975);
DISPLAY INVISIBLE (-2875 3975);
FORCEPROP 1 LAST PATH I126
J 0
(-3200 4100);
DISPLAY 0.936170 (-3200 4100);
PAINT GREEN (-3200 4100);
DISPLAY INVISIBLE (-3200 4100);
FORCEADD TAP..6
(-3200 4150);
FORCEPROP 3 LASTPIN (-3150 4150) SIG_NAME M_K_MA<3>
J 0
(-3140 4160);
DISPLAY 0.659574 (-3140 4160);
PAINT MONO (-3140 4160);
DISPLAY INVISIBLE (-3140 4160);
FORCEPROP 1 LASTPIN (-3150 4150) BN 3
J 0
(-3200 4160);
DISPLAY 0.617021 (-3200 4160);
PAINT PINK (-3200 4160);
FORCEPROP 2 LAST CDS_LIB mstr_standard
J 2
(-3200 4150);
DISPLAY 0.787234 (-3200 4150);
PAINT MONO (-3200 4150);
DISPLAY INVISIBLE (-3200 4150);
FORCEPROP 1 LAST BODY_TYPE PLUMBING
J 0
(-3200 4100);
DISPLAY 1.234043 (-3200 4100);
PAINT GREEN (-3200 4100);
DISPLAY INVISIBLE (-3200 4100);
FORCEPROP 1 LAST HDL_TAP TRUE
J 0
(-2875 4025);
DISPLAY 1.234043 (-2875 4025);
PAINT GREEN (-2875 4025);
DISPLAY INVISIBLE (-2875 4025);
FORCEPROP 1 LAST PATH I127
J 0
(-3200 4150);
DISPLAY 0.936170 (-3200 4150);
PAINT GREEN (-3200 4150);
DISPLAY INVISIBLE (-3200 4150);
FORCEADD TAP..6
(-3200 4050);
FORCEPROP 3 LASTPIN (-3150 4050) SIG_NAME M_K_MA<1>
J 0
(-3140 4060);
DISPLAY 0.659574 (-3140 4060);
PAINT MONO (-3140 4060);
DISPLAY INVISIBLE (-3140 4060);
FORCEPROP 1 LASTPIN (-3150 4050) BN 1
J 0
(-3200 4060);
DISPLAY 0.617021 (-3200 4060);
PAINT PINK (-3200 4060);
FORCEPROP 2 LAST CDS_LIB mstr_standard
J 2
(-3200 4050);
DISPLAY 0.787234 (-3200 4050);
PAINT MONO (-3200 4050);
DISPLAY INVISIBLE (-3200 4050);
FORCEPROP 1 LAST BODY_TYPE PLUMBING
J 0
(-3200 4000);
DISPLAY 1.234043 (-3200 4000);
PAINT GREEN (-3200 4000);
DISPLAY INVISIBLE (-3200 4000);
FORCEPROP 1 LAST HDL_TAP TRUE
J 0
(-2875 3925);
DISPLAY 1.234043 (-2875 3925);
PAINT GREEN (-2875 3925);
DISPLAY INVISIBLE (-2875 3925);
FORCEPROP 1 LAST PATH I128
J 0
(-3200 4050);
DISPLAY 0.936170 (-3200 4050);
PAINT GREEN (-3200 4050);
DISPLAY INVISIBLE (-3200 4050);
FORCEADD TAP..6
(-3200 4000);
FORCEPROP 3 LASTPIN (-3150 4000) SIG_NAME M_K_MA<0>
J 0
(-3140 4010);
DISPLAY 0.659574 (-3140 4010);
PAINT MONO (-3140 4010);
DISPLAY INVISIBLE (-3140 4010);
FORCEPROP 1 LASTPIN (-3150 4000) BN 0
J 0
(-3200 4010);
DISPLAY 0.617021 (-3200 4010);
PAINT PINK (-3200 4010);
FORCEPROP 2 LAST CDS_LIB mstr_standard
J 2
(-3200 4000);
DISPLAY 0.787234 (-3200 4000);
PAINT MONO (-3200 4000);
DISPLAY INVISIBLE (-3200 4000);
FORCEPROP 1 LAST BODY_TYPE PLUMBING
J 0
(-3200 3950);
DISPLAY 1.234043 (-3200 3950);
PAINT GREEN (-3200 3950);
DISPLAY INVISIBLE (-3200 3950);
FORCEPROP 1 LAST HDL_TAP TRUE
J 0
(-2875 3875);
DISPLAY 1.234043 (-2875 3875);
PAINT GREEN (-2875 3875);
DISPLAY INVISIBLE (-2875 3875);
FORCEPROP 1 LAST PATH I129
J 0
(-3200 4000);
DISPLAY 0.936170 (-3200 4000);
PAINT GREEN (-3200 4000);
DISPLAY INVISIBLE (-3200 4000);
FORCEADD TAP..6
R 2
(700 4600);
FORCEPROP 3 LASTPIN (650 4600) SIG_NAME M_K_DQS_DP<11>
J 0
(660 4610);
DISPLAY 0.659574 (660 4610);
PAINT MONO (660 4610);
DISPLAY INVISIBLE (660 4610);
FORCEPROP 1 LASTPIN (650 4600) BN 11
J 2
(700 4610);
DISPLAY 0.617021 (700 4610);
PAINT PINK (700 4610);
FORCEPROP 2 LAST CDS_LIB mstr_standard
J 0
(700 4600);
DISPLAY 0.787234 (700 4600);
PAINT MONO (700 4600);
DISPLAY INVISIBLE (700 4600);
FORCEPROP 1 LAST BODY_TYPE PLUMBING
J 2
(700 4550);
DISPLAY 1.234043 (700 4550);
PAINT GREEN (700 4550);
DISPLAY INVISIBLE (700 4550);
FORCEPROP 1 LAST HDL_TAP TRUE
J 2
(375 4475);
DISPLAY 1.234043 (375 4475);
PAINT GREEN (375 4475);
DISPLAY INVISIBLE (375 4475);
FORCEPROP 1 LAST PATH I13
J 2
(700 4600);
DISPLAY 0.936170 (700 4600);
PAINT GREEN (700 4600);
DISPLAY INVISIBLE (700 4600);
FORCEADD TAP..6
(-3200 3900);
FORCEPROP 3 LASTPIN (-3150 3900) SIG_NAME M_K_BA<1>
J 0
(-3140 3910);
DISPLAY 0.659574 (-3140 3910);
PAINT MONO (-3140 3910);
DISPLAY INVISIBLE (-3140 3910);
FORCEPROP 1 LASTPIN (-3150 3900) BN 1
J 0
(-3200 3910);
DISPLAY 0.617021 (-3200 3910);
PAINT PINK (-3200 3910);
FORCEPROP 2 LAST CDS_LIB mstr_standard
J 0
(-3200 3900);
DISPLAY 0.787234 (-3200 3900);
PAINT MONO (-3200 3900);
DISPLAY INVISIBLE (-3200 3900);
FORCEPROP 1 LAST BODY_TYPE PLUMBING
J 0
(-3200 3850);
DISPLAY 1.234043 (-3200 3850);
PAINT GREEN (-3200 3850);
DISPLAY INVISIBLE (-3200 3850);
FORCEPROP 1 LAST HDL_TAP TRUE
J 0
(-2875 3775);
DISPLAY 1.234043 (-2875 3775);
PAINT GREEN (-2875 3775);
DISPLAY INVISIBLE (-2875 3775);
FORCEPROP 1 LAST PATH I130
J 0
(-3200 3900);
DISPLAY 0.936170 (-3200 3900);
PAINT GREEN (-3200 3900);
DISPLAY INVISIBLE (-3200 3900);
FORCEADD OFFPAGE..1
(-3850 4900);
FORCEPROP 2 LAST $XR0 60 
J 0
(-4101 4900);
DISPLAY 0.638298 (-4101 4900);
PAINT MONO (-4101 4900);
FORCEPROP 2 LAST $XR1 84 
J 0
(-4191 4900);
DISPLAY 0.638298 (-4191 4900);
PAINT MONO (-4191 4900);
FORCEPROP 2 LAST CDS_LIB mstr_standard
J 0
(-3850 4900);
DISPLAY 0.787234 (-3850 4900);
PAINT MONO (-3850 4900);
DISPLAY INVISIBLE (-3850 4900);
FORCEPROP 1 LAST OFFPAGE TRUE
J 0
(-3525 4775);
DISPLAY 0.936170 (-3525 4775);
PAINT GREEN (-3525 4775);
DISPLAY INVISIBLE (-3525 4775);
FORCEPROP 1 LAST COMMENT_BODY TRUE
J 0
(-3725 4800);
DISPLAY 0.936170 (-3725 4800);
PAINT GREEN (-3725 4800);
DISPLAY INVISIBLE (-3725 4800);
FORCEPROP 2 LAST PATH I131
J 0
(-3800 4975);
DISPLAY 0.787234 (-3800 4975);
PAINT MONO (-3800 4975);
DISPLAY INVISIBLE (-3800 4975);
FORCEADD OFFPAGE..1
(-3850 3950);
FORCEPROP 2 LAST $XR0 60 
J 0
(-4101 3950);
DISPLAY 0.638298 (-4101 3950);
PAINT MONO (-4101 3950);
FORCEPROP 2 LAST $XR1 84 
J 0
(-4191 3950);
DISPLAY 0.638298 (-4191 3950);
PAINT MONO (-4191 3950);
FORCEPROP 2 LAST CDS_LIB mstr_standard
J 0
(-3850 3950);
DISPLAY 0.787234 (-3850 3950);
PAINT MONO (-3850 3950);
DISPLAY INVISIBLE (-3850 3950);
FORCEPROP 1 LAST OFFPAGE TRUE
J 0
(-3525 3825);
DISPLAY 0.936170 (-3525 3825);
PAINT GREEN (-3525 3825);
DISPLAY INVISIBLE (-3525 3825);
FORCEPROP 1 LAST COMMENT_BODY TRUE
J 0
(-3725 3850);
DISPLAY 0.936170 (-3725 3850);
PAINT GREEN (-3725 3850);
DISPLAY INVISIBLE (-3725 3850);
FORCEPROP 2 LAST PATH I132
J 0
(-3800 4025);
DISPLAY 0.787234 (-3800 4025);
PAINT MONO (-3800 4025);
DISPLAY INVISIBLE (-3800 4025);
FORCEADD TAP..6
(-3200 3850);
FORCEPROP 3 LASTPIN (-3150 3850) SIG_NAME M_K_BA<0>
J 0
(-3140 3860);
DISPLAY 0.659574 (-3140 3860);
PAINT MONO (-3140 3860);
DISPLAY INVISIBLE (-3140 3860);
FORCEPROP 1 LASTPIN (-3150 3850) BN 0
J 0
(-3200 3860);
DISPLAY 0.617021 (-3200 3860);
PAINT PINK (-3200 3860);
FORCEPROP 2 LAST CDS_LIB mstr_standard
J 0
(-3200 3850);
DISPLAY 0.787234 (-3200 3850);
PAINT MONO (-3200 3850);
DISPLAY INVISIBLE (-3200 3850);
FORCEPROP 1 LAST BODY_TYPE PLUMBING
J 0
(-3200 3800);
DISPLAY 1.234043 (-3200 3800);
PAINT GREEN (-3200 3800);
DISPLAY INVISIBLE (-3200 3800);
FORCEPROP 1 LAST HDL_TAP TRUE
J 0
(-2875 3725);
DISPLAY 1.234043 (-2875 3725);
PAINT GREEN (-2875 3725);
DISPLAY INVISIBLE (-2875 3725);
FORCEPROP 1 LAST PATH I133
J 0
(-3200 3850);
DISPLAY 0.936170 (-3200 3850);
PAINT GREEN (-3200 3850);
DISPLAY INVISIBLE (-3200 3850);
FORCEADD TAP..6
(-3200 3800);
FORCEPROP 3 LASTPIN (-3150 3800) SIG_NAME M_K_BG<1>
J 0
(-3140 3810);
DISPLAY 0.659574 (-3140 3810);
PAINT MONO (-3140 3810);
DISPLAY INVISIBLE (-3140 3810);
FORCEPROP 1 LASTPIN (-3150 3800) BN 1
J 0
(-3200 3810);
DISPLAY 0.617021 (-3200 3810);
PAINT PINK (-3200 3810);
FORCEPROP 2 LAST CDS_LIB mstr_standard
J 0
(-3200 3800);
DISPLAY 0.787234 (-3200 3800);
PAINT MONO (-3200 3800);
DISPLAY INVISIBLE (-3200 3800);
FORCEPROP 1 LAST BODY_TYPE PLUMBING
J 0
(-3200 3750);
DISPLAY 1.234043 (-3200 3750);
PAINT GREEN (-3200 3750);
DISPLAY INVISIBLE (-3200 3750);
FORCEPROP 1 LAST HDL_TAP TRUE
J 0
(-2875 3675);
DISPLAY 1.234043 (-2875 3675);
PAINT GREEN (-2875 3675);
DISPLAY INVISIBLE (-2875 3675);
FORCEPROP 1 LAST PATH I134
J 0
(-3200 3800);
DISPLAY 0.936170 (-3200 3800);
PAINT GREEN (-3200 3800);
DISPLAY INVISIBLE (-3200 3800);
FORCEADD TAP..6
(-3200 3750);
FORCEPROP 3 LASTPIN (-3150 3750) SIG_NAME M_K_BG<0>
J 0
(-3140 3760);
DISPLAY 0.659574 (-3140 3760);
PAINT MONO (-3140 3760);
DISPLAY INVISIBLE (-3140 3760);
FORCEPROP 1 LASTPIN (-3150 3750) BN 0
J 0
(-3200 3760);
DISPLAY 0.617021 (-3200 3760);
PAINT PINK (-3200 3760);
FORCEPROP 2 LAST CDS_LIB mstr_standard
J 0
(-3200 3750);
DISPLAY 0.787234 (-3200 3750);
PAINT MONO (-3200 3750);
DISPLAY INVISIBLE (-3200 3750);
FORCEPROP 1 LAST BODY_TYPE PLUMBING
J 0
(-3200 3700);
DISPLAY 1.234043 (-3200 3700);
PAINT GREEN (-3200 3700);
DISPLAY INVISIBLE (-3200 3700);
FORCEPROP 1 LAST HDL_TAP TRUE
J 0
(-2875 3625);
DISPLAY 1.234043 (-2875 3625);
PAINT GREEN (-2875 3625);
DISPLAY INVISIBLE (-2875 3625);
FORCEPROP 1 LAST PATH I135
J 0
(-3200 3750);
DISPLAY 0.936170 (-3200 3750);
PAINT GREEN (-3200 3750);
DISPLAY INVISIBLE (-3200 3750);
FORCEADD OFFPAGE..1
(-3850 3450);
FORCEPROP 2 LAST $XR0 60 
J 0
(-4101 3450);
DISPLAY 0.638298 (-4101 3450);
PAINT MONO (-4101 3450);
FORCEPROP 2 LAST $XR1 84 
J 0
(-4191 3450);
DISPLAY 0.638298 (-4191 3450);
PAINT MONO (-4191 3450);
FORCEPROP 2 LAST CDS_LIB mstr_standard
J 0
(-3850 3450);
DISPLAY 0.787234 (-3850 3450);
PAINT MONO (-3850 3450);
DISPLAY INVISIBLE (-3850 3450);
FORCEPROP 1 LAST OFFPAGE TRUE
J 0
(-3525 3325);
DISPLAY 0.936170 (-3525 3325);
PAINT GREEN (-3525 3325);
DISPLAY INVISIBLE (-3525 3325);
FORCEPROP 1 LAST COMMENT_BODY TRUE
J 0
(-3725 3350);
DISPLAY 0.936170 (-3725 3350);
PAINT GREEN (-3725 3350);
DISPLAY INVISIBLE (-3725 3350);
FORCEPROP 2 LAST PATH I136
J 0
(-3800 3525);
DISPLAY 0.787234 (-3800 3525);
PAINT MONO (-3800 3525);
DISPLAY INVISIBLE (-3800 3525);
FORCEADD OFFPAGE..1
(-3850 3850);
FORCEPROP 2 LAST $XR0 60 
J 0
(-4101 3850);
DISPLAY 0.638298 (-4101 3850);
PAINT MONO (-4101 3850);
FORCEPROP 2 LAST $XR1 84 
J 0
(-4191 3850);
DISPLAY 0.638298 (-4191 3850);
PAINT MONO (-4191 3850);
FORCEPROP 2 LAST CDS_LIB mstr_standard
J 0
(-3850 3850);
DISPLAY 0.787234 (-3850 3850);
PAINT MONO (-3850 3850);
DISPLAY INVISIBLE (-3850 3850);
FORCEPROP 1 LAST OFFPAGE TRUE
J 0
(-3525 3725);
DISPLAY 0.936170 (-3525 3725);
PAINT GREEN (-3525 3725);
DISPLAY INVISIBLE (-3525 3725);
FORCEPROP 1 LAST COMMENT_BODY TRUE
J 0
(-3725 3750);
DISPLAY 0.936170 (-3725 3750);
PAINT GREEN (-3725 3750);
DISPLAY INVISIBLE (-3725 3750);
FORCEPROP 2 LAST PATH I137
J 0
(-3800 3925);
DISPLAY 0.787234 (-3800 3925);
PAINT MONO (-3800 3925);
DISPLAY INVISIBLE (-3800 3925);
FORCEADD TAP..6
(-3200 2800);
FORCEPROP 3 LASTPIN (-3150 2800) SIG_NAME M_K_ECC<6>
J 0
(-3140 2810);
DISPLAY 0.659574 (-3140 2810);
PAINT MONO (-3140 2810);
DISPLAY INVISIBLE (-3140 2810);
FORCEPROP 1 LASTPIN (-3150 2800) BN 6
J 0
(-3200 2810);
DISPLAY 0.617021 (-3200 2810);
PAINT PINK (-3200 2810);
FORCEPROP 2 LAST CDS_LIB mstr_standard
J 0
(-3200 2800);
DISPLAY 0.787234 (-3200 2800);
PAINT MONO (-3200 2800);
DISPLAY INVISIBLE (-3200 2800);
FORCEPROP 1 LAST BODY_TYPE PLUMBING
J 0
(-3200 2750);
DISPLAY 1.234043 (-3200 2750);
PAINT GREEN (-3200 2750);
DISPLAY INVISIBLE (-3200 2750);
FORCEPROP 1 LAST HDL_TAP TRUE
J 0
(-2875 2675);
DISPLAY 1.234043 (-2875 2675);
PAINT GREEN (-2875 2675);
DISPLAY INVISIBLE (-2875 2675);
FORCEPROP 1 LAST PATH I138
J 0
(-3200 2800);
DISPLAY 0.936170 (-3200 2800);
PAINT GREEN (-3200 2800);
DISPLAY INVISIBLE (-3200 2800);
FORCEADD TAP..6
(-3200 2750);
FORCEPROP 3 LASTPIN (-3150 2750) SIG_NAME M_K_ECC<7>
J 0
(-3140 2760);
DISPLAY 0.659574 (-3140 2760);
PAINT MONO (-3140 2760);
DISPLAY INVISIBLE (-3140 2760);
FORCEPROP 1 LASTPIN (-3150 2750) BN 7
J 0
(-3200 2760);
DISPLAY 0.617021 (-3200 2760);
PAINT PINK (-3200 2760);
FORCEPROP 2 LAST CDS_LIB mstr_standard
J 0
(-3200 2750);
DISPLAY 0.787234 (-3200 2750);
PAINT MONO (-3200 2750);
DISPLAY INVISIBLE (-3200 2750);
FORCEPROP 1 LAST BODY_TYPE PLUMBING
J 0
(-3200 2700);
DISPLAY 1.234043 (-3200 2700);
PAINT GREEN (-3200 2700);
DISPLAY INVISIBLE (-3200 2700);
FORCEPROP 1 LAST HDL_TAP TRUE
J 0
(-2875 2625);
DISPLAY 1.234043 (-2875 2625);
PAINT GREEN (-2875 2625);
DISPLAY INVISIBLE (-2875 2625);
FORCEPROP 1 LAST PATH I139
J 0
(-3200 2750);
DISPLAY 0.936170 (-3200 2750);
PAINT GREEN (-3200 2750);
DISPLAY INVISIBLE (-3200 2750);
FORCEADD TAP..6
R 2
(700 4700);
FORCEPROP 3 LASTPIN (650 4700) SIG_NAME M_K_DQS_DP<12>
J 0
(660 4710);
DISPLAY 0.659574 (660 4710);
PAINT MONO (660 4710);
DISPLAY INVISIBLE (660 4710);
FORCEPROP 1 LASTPIN (650 4700) BN 12
J 2
(700 4710);
DISPLAY 0.617021 (700 4710);
PAINT PINK (700 4710);
FORCEPROP 2 LAST CDS_LIB mstr_standard
J 0
(700 4700);
DISPLAY 0.787234 (700 4700);
PAINT MONO (700 4700);
DISPLAY INVISIBLE (700 4700);
FORCEPROP 1 LAST BODY_TYPE PLUMBING
J 2
(700 4650);
DISPLAY 1.234043 (700 4650);
PAINT GREEN (700 4650);
DISPLAY INVISIBLE (700 4650);
FORCEPROP 1 LAST HDL_TAP TRUE
J 2
(375 4575);
DISPLAY 1.234043 (375 4575);
PAINT GREEN (375 4575);
DISPLAY INVISIBLE (375 4575);
FORCEPROP 1 LAST PATH I14
J 2
(700 4700);
DISPLAY 0.936170 (700 4700);
PAINT GREEN (700 4700);
DISPLAY INVISIBLE (700 4700);
FORCEADD TAP..6
(-3200 2700);
FORCEPROP 3 LASTPIN (-3150 2700) SIG_NAME M_K_ECC<4>
J 0
(-3140 2710);
DISPLAY 0.659574 (-3140 2710);
PAINT MONO (-3140 2710);
DISPLAY INVISIBLE (-3140 2710);
FORCEPROP 1 LASTPIN (-3150 2700) BN 4
J 0
(-3200 2710);
DISPLAY 0.617021 (-3200 2710);
PAINT PINK (-3200 2710);
FORCEPROP 2 LAST CDS_LIB mstr_standard
J 0
(-3200 2700);
DISPLAY 0.787234 (-3200 2700);
PAINT MONO (-3200 2700);
DISPLAY INVISIBLE (-3200 2700);
FORCEPROP 1 LAST BODY_TYPE PLUMBING
J 0
(-3200 2650);
DISPLAY 1.234043 (-3200 2650);
PAINT GREEN (-3200 2650);
DISPLAY INVISIBLE (-3200 2650);
FORCEPROP 1 LAST HDL_TAP TRUE
J 0
(-2875 2575);
DISPLAY 1.234043 (-2875 2575);
PAINT GREEN (-2875 2575);
DISPLAY INVISIBLE (-2875 2575);
FORCEPROP 1 LAST PATH I140
J 0
(-3200 2700);
DISPLAY 0.936170 (-3200 2700);
PAINT GREEN (-3200 2700);
DISPLAY INVISIBLE (-3200 2700);
FORCEADD TAP..6
(-3200 2650);
FORCEPROP 3 LASTPIN (-3150 2650) SIG_NAME M_K_ECC<5>
J 0
(-3140 2660);
DISPLAY 0.659574 (-3140 2660);
PAINT MONO (-3140 2660);
DISPLAY INVISIBLE (-3140 2660);
FORCEPROP 1 LASTPIN (-3150 2650) BN 5
J 0
(-3200 2660);
DISPLAY 0.617021 (-3200 2660);
PAINT PINK (-3200 2660);
FORCEPROP 2 LAST CDS_LIB mstr_standard
J 0
(-3200 2650);
DISPLAY 0.787234 (-3200 2650);
PAINT MONO (-3200 2650);
DISPLAY INVISIBLE (-3200 2650);
FORCEPROP 1 LAST BODY_TYPE PLUMBING
J 0
(-3200 2600);
DISPLAY 1.234043 (-3200 2600);
PAINT GREEN (-3200 2600);
DISPLAY INVISIBLE (-3200 2600);
FORCEPROP 1 LAST HDL_TAP TRUE
J 0
(-2875 2525);
DISPLAY 1.234043 (-2875 2525);
PAINT GREEN (-2875 2525);
DISPLAY INVISIBLE (-2875 2525);
FORCEPROP 1 LAST PATH I141
J 0
(-3200 2650);
DISPLAY 0.936170 (-3200 2650);
PAINT GREEN (-3200 2650);
DISPLAY INVISIBLE (-3200 2650);
FORCEADD TAP..6
(-3200 2600);
FORCEPROP 3 LASTPIN (-3150 2600) SIG_NAME M_K_ECC<2>
J 0
(-3140 2610);
DISPLAY 0.659574 (-3140 2610);
PAINT MONO (-3140 2610);
DISPLAY INVISIBLE (-3140 2610);
FORCEPROP 1 LASTPIN (-3150 2600) BN 2
J 0
(-3200 2610);
DISPLAY 0.617021 (-3200 2610);
PAINT PINK (-3200 2610);
FORCEPROP 2 LAST CDS_LIB mstr_standard
J 0
(-3200 2600);
DISPLAY 0.787234 (-3200 2600);
PAINT MONO (-3200 2600);
DISPLAY INVISIBLE (-3200 2600);
FORCEPROP 1 LAST BODY_TYPE PLUMBING
J 0
(-3200 2550);
DISPLAY 1.234043 (-3200 2550);
PAINT GREEN (-3200 2550);
DISPLAY INVISIBLE (-3200 2550);
FORCEPROP 1 LAST HDL_TAP TRUE
J 0
(-2875 2475);
DISPLAY 1.234043 (-2875 2475);
PAINT GREEN (-2875 2475);
DISPLAY INVISIBLE (-2875 2475);
FORCEPROP 1 LAST PATH I142
J 0
(-3200 2600);
DISPLAY 0.936170 (-3200 2600);
PAINT GREEN (-3200 2600);
DISPLAY INVISIBLE (-3200 2600);
FORCEADD TAP..6
(-3200 2550);
FORCEPROP 3 LASTPIN (-3150 2550) SIG_NAME M_K_ECC<3>
J 0
(-3140 2560);
DISPLAY 0.659574 (-3140 2560);
PAINT MONO (-3140 2560);
DISPLAY INVISIBLE (-3140 2560);
FORCEPROP 1 LASTPIN (-3150 2550) BN 3
J 0
(-3200 2560);
DISPLAY 0.617021 (-3200 2560);
PAINT PINK (-3200 2560);
FORCEPROP 2 LAST CDS_LIB mstr_standard
J 0
(-3200 2550);
DISPLAY 0.787234 (-3200 2550);
PAINT MONO (-3200 2550);
DISPLAY INVISIBLE (-3200 2550);
FORCEPROP 1 LAST BODY_TYPE PLUMBING
J 0
(-3200 2500);
DISPLAY 1.234043 (-3200 2500);
PAINT GREEN (-3200 2500);
DISPLAY INVISIBLE (-3200 2500);
FORCEPROP 1 LAST HDL_TAP TRUE
J 0
(-2875 2425);
DISPLAY 1.234043 (-2875 2425);
PAINT GREEN (-2875 2425);
DISPLAY INVISIBLE (-2875 2425);
FORCEPROP 1 LAST PATH I143
J 0
(-3200 2550);
DISPLAY 0.936170 (-3200 2550);
PAINT GREEN (-3200 2550);
DISPLAY INVISIBLE (-3200 2550);
FORCEADD TAP..6
(-3200 2500);
FORCEPROP 3 LASTPIN (-3150 2500) SIG_NAME M_K_ECC<0>
J 0
(-3140 2510);
DISPLAY 0.659574 (-3140 2510);
PAINT MONO (-3140 2510);
DISPLAY INVISIBLE (-3140 2510);
FORCEPROP 1 LASTPIN (-3150 2500) BN 0
J 0
(-3200 2510);
DISPLAY 0.617021 (-3200 2510);
PAINT PINK (-3200 2510);
FORCEPROP 2 LAST CDS_LIB mstr_standard
J 0
(-3200 2500);
DISPLAY 0.787234 (-3200 2500);
PAINT MONO (-3200 2500);
DISPLAY INVISIBLE (-3200 2500);
FORCEPROP 1 LAST BODY_TYPE PLUMBING
J 0
(-3200 2450);
DISPLAY 1.234043 (-3200 2450);
PAINT GREEN (-3200 2450);
DISPLAY INVISIBLE (-3200 2450);
FORCEPROP 1 LAST HDL_TAP TRUE
J 0
(-2875 2375);
DISPLAY 1.234043 (-2875 2375);
PAINT GREEN (-2875 2375);
DISPLAY INVISIBLE (-2875 2375);
FORCEPROP 1 LAST PATH I144
J 0
(-3200 2500);
DISPLAY 0.936170 (-3200 2500);
PAINT GREEN (-3200 2500);
DISPLAY INVISIBLE (-3200 2500);
FORCEADD TAP..6
(-3200 2450);
FORCEPROP 3 LASTPIN (-3150 2450) SIG_NAME M_K_ECC<1>
J 0
(-3140 2460);
DISPLAY 0.659574 (-3140 2460);
PAINT MONO (-3140 2460);
DISPLAY INVISIBLE (-3140 2460);
FORCEPROP 1 LASTPIN (-3150 2450) BN 1
J 0
(-3200 2460);
DISPLAY 0.617021 (-3200 2460);
PAINT PINK (-3200 2460);
FORCEPROP 2 LAST CDS_LIB mstr_standard
J 0
(-3200 2450);
DISPLAY 0.787234 (-3200 2450);
PAINT MONO (-3200 2450);
DISPLAY INVISIBLE (-3200 2450);
FORCEPROP 1 LAST BODY_TYPE PLUMBING
J 0
(-3200 2400);
DISPLAY 1.234043 (-3200 2400);
PAINT GREEN (-3200 2400);
DISPLAY INVISIBLE (-3200 2400);
FORCEPROP 1 LAST HDL_TAP TRUE
J 0
(-2875 2325);
DISPLAY 1.234043 (-2875 2325);
PAINT GREEN (-2875 2325);
DISPLAY INVISIBLE (-2875 2325);
FORCEPROP 1 LAST PATH I145
J 0
(-3200 2450);
DISPLAY 0.936170 (-3200 2450);
PAINT GREEN (-3200 2450);
DISPLAY INVISIBLE (-3200 2450);
FORCEADD OFFPAGE..1
(-3850 2800);
FORCEPROP 2 LAST $XR0 60 
J 0
(-4101 2800);
DISPLAY 0.638298 (-4101 2800);
PAINT MONO (-4101 2800);
FORCEPROP 2 LAST $XR1 84 
J 0
(-4191 2800);
DISPLAY 0.638298 (-4191 2800);
PAINT MONO (-4191 2800);
FORCEPROP 2 LAST CDS_LIB mstr_standard
J 0
(-3850 2800);
DISPLAY 0.787234 (-3850 2800);
PAINT MONO (-3850 2800);
DISPLAY INVISIBLE (-3850 2800);
FORCEPROP 1 LAST OFFPAGE TRUE
J 0
(-3525 2675);
DISPLAY 0.936170 (-3525 2675);
PAINT GREEN (-3525 2675);
DISPLAY INVISIBLE (-3525 2675);
FORCEPROP 1 LAST COMMENT_BODY TRUE
J 0
(-3725 2700);
DISPLAY 0.936170 (-3725 2700);
PAINT GREEN (-3725 2700);
DISPLAY INVISIBLE (-3725 2700);
FORCEPROP 2 LAST PATH I146
J 0
(-3800 2875);
DISPLAY 0.787234 (-3800 2875);
PAINT MONO (-3800 2875);
DISPLAY INVISIBLE (-3800 2875);
FORCEADD OFFPAGE..1
(-4000 2150);
FORCEPROP 2 LAST $XR0 60 
J 0
(-4251 2150);
DISPLAY 0.638298 (-4251 2150);
PAINT MONO (-4251 2150);
FORCEPROP 2 LAST $XR1 84 
J 0
(-4341 2150);
DISPLAY 0.638298 (-4341 2150);
PAINT MONO (-4341 2150);
FORCEPROP 2 LAST CDS_LIB mstr_standard
J 0
(-4000 2150);
DISPLAY 0.787234 (-4000 2150);
PAINT MONO (-4000 2150);
DISPLAY INVISIBLE (-4000 2150);
FORCEPROP 1 LAST OFFPAGE TRUE
J 0
(-3675 2025);
DISPLAY 0.936170 (-3675 2025);
PAINT GREEN (-3675 2025);
DISPLAY INVISIBLE (-3675 2025);
FORCEPROP 1 LAST COMMENT_BODY TRUE
J 0
(-3875 2050);
DISPLAY 0.936170 (-3875 2050);
PAINT GREEN (-3875 2050);
DISPLAY INVISIBLE (-3875 2050);
FORCEPROP 2 LAST PATH I147
J 0
(-3950 2225);
DISPLAY 0.787234 (-3950 2225);
PAINT MONO (-3950 2225);
DISPLAY INVISIBLE (-3950 2225);
FORCEADD OFFPAGE..5
(-4025 2200);
FORCEPROP 2 LAST $XR0 84 
J 0
(-4249 2200);
DISPLAY 0.638298 (-4249 2200);
PAINT MONO (-4249 2200);
FORCEPROP 2 LAST $XR1 60 
J 0
(-4339 2200);
DISPLAY 0.638298 (-4339 2200);
PAINT MONO (-4339 2200);
FORCEPROP 2 LAST CDS_LIB mstr_standard
J 0
(-4025 2200);
DISPLAY 0.787234 (-4025 2200);
PAINT MONO (-4025 2200);
DISPLAY INVISIBLE (-4025 2200);
FORCEPROP 1 LAST OFFPAGE TRUE
J 0
(-3700 2075);
DISPLAY 1.404255 (-3700 2075);
PAINT GREEN (-3700 2075);
DISPLAY INVISIBLE (-3700 2075);
FORCEPROP 1 LAST COMMENT_BODY TRUE
J 0
(-3925 2125);
DISPLAY 1.404255 (-3925 2125);
PAINT GREEN (-3925 2125);
DISPLAY INVISIBLE (-3925 2125);
FORCEPROP 2 LAST PATH I148
J 0
(-3975 2275);
DISPLAY 0.787234 (-3975 2275);
PAINT MONO (-3975 2275);
DISPLAY INVISIBLE (-3975 2275);
FORCEADD OFFPAGE..1
(-3850 2750);
FORCEPROP 2 LAST $XR0 55 
J 0
(-4101 2750);
DISPLAY 0.638298 (-4101 2750);
PAINT MONO (-4101 2750);
FORCEPROP 2 LAST $XR1 84 
J 0
(-4191 2750);
DISPLAY 0.638298 (-4191 2750);
PAINT MONO (-4191 2750);
FORCEPROP 2 LAST $XR2 85 
J 0
(-4281 2750);
DISPLAY 0.638298 (-4281 2750);
PAINT MONO (-4281 2750);
FORCEPROP 2 LAST $XR3 86 
J 0
(-4371 2750);
DISPLAY 0.638298 (-4371 2750);
PAINT MONO (-4371 2750);
FORCEPROP 2 LAST $XR4 87 
J 0
(-4461 2750);
DISPLAY 0.638298 (-4461 2750);
PAINT MONO (-4461 2750);
FORCEPROP 2 LAST $XR5 88 
J 0
(-4551 2750);
DISPLAY 0.638298 (-4551 2750);
PAINT MONO (-4551 2750);
FORCEPROP 2 LAST CDS_LIB mstr_standard
J 0
(-3850 2750);
DISPLAY 0.787234 (-3850 2750);
PAINT MONO (-3850 2750);
DISPLAY INVISIBLE (-3850 2750);
FORCEPROP 1 LAST OFFPAGE TRUE
J 0
(-3525 2625);
DISPLAY 0.936170 (-3525 2625);
PAINT GREEN (-3525 2625);
DISPLAY INVISIBLE (-3525 2625);
FORCEPROP 1 LAST COMMENT_BODY TRUE
J 0
(-3725 2650);
DISPLAY 0.936170 (-3725 2650);
PAINT GREEN (-3725 2650);
DISPLAY INVISIBLE (-3725 2650);
FORCEPROP 2 LAST PATH I149
J 0
(-3800 2825);
DISPLAY 0.787234 (-3800 2825);
PAINT MONO (-3800 2825);
DISPLAY INVISIBLE (-3800 2825);
FORCEADD TAP..6
R 2
(700 4800);
FORCEPROP 3 LASTPIN (650 4800) SIG_NAME M_K_DQS_DP<13>
J 0
(660 4810);
DISPLAY 0.659574 (660 4810);
PAINT MONO (660 4810);
DISPLAY INVISIBLE (660 4810);
FORCEPROP 1 LASTPIN (650 4800) BN 13
J 2
(700 4810);
DISPLAY 0.617021 (700 4810);
PAINT PINK (700 4810);
FORCEPROP 2 LAST CDS_LIB mstr_standard
J 0
(700 4800);
DISPLAY 0.787234 (700 4800);
PAINT MONO (700 4800);
DISPLAY INVISIBLE (700 4800);
FORCEPROP 1 LAST BODY_TYPE PLUMBING
J 2
(700 4750);
DISPLAY 1.234043 (700 4750);
PAINT GREEN (700 4750);
DISPLAY INVISIBLE (700 4750);
FORCEPROP 1 LAST HDL_TAP TRUE
J 2
(375 4675);
DISPLAY 1.234043 (375 4675);
PAINT GREEN (375 4675);
DISPLAY INVISIBLE (375 4675);
FORCEPROP 1 LAST PATH I15
J 2
(700 4800);
DISPLAY 0.936170 (700 4800);
PAINT GREEN (700 4800);
DISPLAY INVISIBLE (700 4800);
FORCEADD OFFPAGE..6
(-3850 2850);
FORCEPROP 2 LAST $XR0 60 
J 0
(-4099 2850);
DISPLAY 0.638298 (-4099 2850);
PAINT MONO (-4099 2850);
FORCEPROP 2 LAST $XR1 84 
J 0
(-4189 2850);
DISPLAY 0.638298 (-4189 2850);
PAINT MONO (-4189 2850);
FORCEPROP 2 LAST CDS_LIB mstr_standard
J 0
(-3850 2850);
DISPLAY 0.787234 (-3850 2850);
PAINT MONO (-3850 2850);
DISPLAY INVISIBLE (-3850 2850);
FORCEPROP 1 LAST OFFPAGE TRUE
J 0
(-3525 2725);
DISPLAY 0.936170 (-3525 2725);
PAINT GREEN (-3525 2725);
DISPLAY INVISIBLE (-3525 2725);
FORCEPROP 1 LAST COMMENT_BODY TRUE
J 0
(-3750 2775);
DISPLAY 0.936170 (-3750 2775);
PAINT GREEN (-3750 2775);
DISPLAY INVISIBLE (-3750 2775);
FORCEPROP 2 LAST PATH I150
J 0
(-3800 2925);
DISPLAY 0.787234 (-3800 2925);
PAINT MONO (-3800 2925);
DISPLAY INVISIBLE (-3800 2925);
FORCEADD TAP..6
(-3200 3350);
FORCEPROP 3 LASTPIN (-3150 3350) SIG_NAME M_K_CS_N<3>
J 0
(-3140 3360);
DISPLAY 0.659574 (-3140 3360);
PAINT MONO (-3140 3360);
DISPLAY INVISIBLE (-3140 3360);
FORCEPROP 1 LASTPIN (-3150 3350) BN 3
J 0
(-3200 3360);
DISPLAY 0.617021 (-3200 3360);
PAINT PINK (-3200 3360);
FORCEPROP 2 LAST CDS_LIB mstr_standard
J 0
(-3200 3350);
DISPLAY 0.787234 (-3200 3350);
PAINT MONO (-3200 3350);
DISPLAY INVISIBLE (-3200 3350);
FORCEPROP 1 LAST BODY_TYPE PLUMBING
J 0
(-3200 3300);
DISPLAY 1.234043 (-3200 3300);
PAINT GREEN (-3200 3300);
DISPLAY INVISIBLE (-3200 3300);
FORCEPROP 1 LAST HDL_TAP TRUE
J 0
(-2875 3225);
DISPLAY 1.234043 (-2875 3225);
PAINT GREEN (-2875 3225);
DISPLAY INVISIBLE (-2875 3225);
FORCEPROP 1 LAST PATH I152
J 0
(-3200 3350);
DISPLAY 0.936170 (-3200 3350);
PAINT GREEN (-3200 3350);
DISPLAY INVISIBLE (-3200 3350);
FORCEADD TAP..6
(-3200 3300);
FORCEPROP 3 LASTPIN (-3150 3300) SIG_NAME M_K_CS_N<2>
J 0
(-3140 3310);
DISPLAY 0.659574 (-3140 3310);
PAINT MONO (-3140 3310);
DISPLAY INVISIBLE (-3140 3310);
FORCEPROP 1 LASTPIN (-3150 3300) BN 2
J 0
(-3200 3310);
DISPLAY 0.617021 (-3200 3310);
PAINT PINK (-3200 3310);
FORCEPROP 2 LAST CDS_LIB mstr_standard
J 0
(-3200 3300);
DISPLAY 0.787234 (-3200 3300);
PAINT MONO (-3200 3300);
DISPLAY INVISIBLE (-3200 3300);
FORCEPROP 1 LAST BODY_TYPE PLUMBING
J 0
(-3200 3250);
DISPLAY 1.234043 (-3200 3250);
PAINT GREEN (-3200 3250);
DISPLAY INVISIBLE (-3200 3250);
FORCEPROP 1 LAST HDL_TAP TRUE
J 0
(-2875 3175);
DISPLAY 1.234043 (-2875 3175);
PAINT GREEN (-2875 3175);
DISPLAY INVISIBLE (-2875 3175);
FORCEPROP 1 LAST PATH I153
J 0
(-3200 3300);
DISPLAY 0.936170 (-3200 3300);
PAINT GREEN (-3200 3300);
DISPLAY INVISIBLE (-3200 3300);
FORCEADD TAP..6
(-3200 3050);
FORCEPROP 3 LASTPIN (-3150 3050) SIG_NAME M_K_CKE<0>
J 0
(-3140 3060);
DISPLAY 0.659574 (-3140 3060);
PAINT MONO (-3140 3060);
DISPLAY INVISIBLE (-3140 3060);
FORCEPROP 1 LASTPIN (-3150 3050) BN 0
J 0
(-3200 3060);
DISPLAY 0.617021 (-3200 3060);
PAINT PINK (-3200 3060);
FORCEPROP 2 LAST CDS_LIB mstr_standard
J 0
(-3200 3050);
DISPLAY 0.787234 (-3200 3050);
PAINT MONO (-3200 3050);
DISPLAY INVISIBLE (-3200 3050);
FORCEPROP 1 LAST BODY_TYPE PLUMBING
J 0
(-3200 3000);
DISPLAY 1.234043 (-3200 3000);
PAINT GREEN (-3200 3000);
DISPLAY INVISIBLE (-3200 3000);
FORCEPROP 1 LAST HDL_TAP TRUE
J 0
(-2875 2925);
DISPLAY 1.234043 (-2875 2925);
PAINT GREEN (-2875 2925);
DISPLAY INVISIBLE (-2875 2925);
FORCEPROP 1 LAST PATH I154
J 0
(-3200 3050);
DISPLAY 0.936170 (-3200 3050);
PAINT GREEN (-3200 3050);
DISPLAY INVISIBLE (-3200 3050);
FORCEADD TAP..6
(-3200 2900);
FORCEPROP 3 LASTPIN (-3150 2900) SIG_NAME M_K_ODT<0>
J 0
(-3140 2910);
DISPLAY 0.659574 (-3140 2910);
PAINT MONO (-3140 2910);
DISPLAY INVISIBLE (-3140 2910);
FORCEPROP 1 LASTPIN (-3150 2900) BN 0
J 0
(-3200 2910);
DISPLAY 0.617021 (-3200 2910);
PAINT PINK (-3200 2910);
FORCEPROP 2 LAST CDS_LIB mstr_standard
J 0
(-3200 2900);
DISPLAY 0.787234 (-3200 2900);
PAINT MONO (-3200 2900);
DISPLAY INVISIBLE (-3200 2900);
FORCEPROP 1 LAST BODY_TYPE PLUMBING
J 0
(-3200 2850);
DISPLAY 1.234043 (-3200 2850);
PAINT GREEN (-3200 2850);
DISPLAY INVISIBLE (-3200 2850);
FORCEPROP 1 LAST HDL_TAP TRUE
J 0
(-2875 2775);
DISPLAY 1.234043 (-2875 2775);
PAINT GREEN (-2875 2775);
DISPLAY INVISIBLE (-2875 2775);
FORCEPROP 1 LAST PATH I155
J 0
(-3200 2900);
DISPLAY 0.936170 (-3200 2900);
PAINT GREEN (-3200 2900);
DISPLAY INVISIBLE (-3200 2900);
FORCEADD TAP..6
(-3550 3550);
FORCEPROP 3 LASTPIN (-3500 3550) SIG_NAME M_K_CLK_DP<0>
J 0
(-3490 3560);
DISPLAY 0.659574 (-3490 3560);
PAINT MONO (-3490 3560);
DISPLAY INVISIBLE (-3490 3560);
FORCEPROP 1 LASTPIN (-3500 3550) BN 0
J 0
(-3550 3560);
DISPLAY 0.617021 (-3550 3560);
PAINT PINK (-3550 3560);
FORCEPROP 2 LAST CDS_LIB mstr_standard
J 0
(-3550 3550);
DISPLAY 0.787234 (-3550 3550);
PAINT MONO (-3550 3550);
DISPLAY INVISIBLE (-3550 3550);
FORCEPROP 1 LAST BODY_TYPE PLUMBING
J 0
(-3550 3500);
DISPLAY 1.234043 (-3550 3500);
PAINT GREEN (-3550 3500);
DISPLAY INVISIBLE (-3550 3500);
FORCEPROP 1 LAST HDL_TAP TRUE
J 0
(-3225 3425);
DISPLAY 1.234043 (-3225 3425);
PAINT GREEN (-3225 3425);
DISPLAY INVISIBLE (-3225 3425);
FORCEPROP 1 LAST PATH I156
J 0
(-3550 3550);
DISPLAY 0.936170 (-3550 3550);
PAINT GREEN (-3550 3550);
DISPLAY INVISIBLE (-3550 3550);
FORCEADD OFFPAGE..1
(-4250 3700);
FORCEPROP 2 LAST $XR0 60 
J 0
(-4501 3700);
DISPLAY 0.638298 (-4501 3700);
PAINT MONO (-4501 3700);
FORCEPROP 2 LAST $XR1 84 
J 0
(-4591 3700);
DISPLAY 0.638298 (-4591 3700);
PAINT MONO (-4591 3700);
FORCEPROP 2 LAST CDS_LIB mstr_standard
J 0
(-4250 3700);
DISPLAY 0.787234 (-4250 3700);
PAINT MONO (-4250 3700);
DISPLAY INVISIBLE (-4250 3700);
FORCEPROP 1 LAST OFFPAGE TRUE
J 0
(-3925 3575);
DISPLAY 0.936170 (-3925 3575);
PAINT GREEN (-3925 3575);
DISPLAY INVISIBLE (-3925 3575);
FORCEPROP 1 LAST COMMENT_BODY TRUE
J 0
(-4125 3600);
DISPLAY 0.936170 (-4125 3600);
PAINT GREEN (-4125 3600);
DISPLAY INVISIBLE (-4125 3600);
FORCEPROP 2 LAST PATH I157
J 0
(-4200 3775);
DISPLAY 0.787234 (-4200 3775);
PAINT MONO (-4200 3775);
DISPLAY INVISIBLE (-4200 3775);
FORCEADD OFFPAGE..1
(-4250 3750);
FORCEPROP 2 LAST $XR0 60 
J 0
(-4501 3750);
DISPLAY 0.638298 (-4501 3750);
PAINT MONO (-4501 3750);
FORCEPROP 2 LAST $XR1 84 
J 0
(-4591 3750);
DISPLAY 0.638298 (-4591 3750);
PAINT MONO (-4591 3750);
FORCEPROP 2 LAST CDS_LIB mstr_standard
J 0
(-4250 3750);
DISPLAY 0.787234 (-4250 3750);
PAINT MONO (-4250 3750);
DISPLAY INVISIBLE (-4250 3750);
FORCEPROP 1 LAST OFFPAGE TRUE
J 0
(-3925 3625);
DISPLAY 0.936170 (-3925 3625);
PAINT GREEN (-3925 3625);
DISPLAY INVISIBLE (-3925 3625);
FORCEPROP 1 LAST COMMENT_BODY TRUE
J 0
(-4125 3650);
DISPLAY 0.936170 (-4125 3650);
PAINT GREEN (-4125 3650);
DISPLAY INVISIBLE (-4125 3650);
FORCEPROP 2 LAST PATH I158
J 0
(-4200 3825);
DISPLAY 0.787234 (-4200 3825);
PAINT MONO (-4200 3825);
DISPLAY INVISIBLE (-4200 3825);
FORCEADD TAP..6
(-3700 3500);
FORCEPROP 3 LASTPIN (-3650 3500) SIG_NAME M_K_CLK_DN<0>
J 0
(-3640 3510);
DISPLAY 0.659574 (-3640 3510);
PAINT MONO (-3640 3510);
DISPLAY INVISIBLE (-3640 3510);
FORCEPROP 1 LASTPIN (-3650 3500) BN 0
J 0
(-3700 3510);
DISPLAY 0.617021 (-3700 3510);
PAINT PINK (-3700 3510);
FORCEPROP 2 LAST CDS_LIB mstr_standard
J 0
(-3700 3500);
DISPLAY 0.787234 (-3700 3500);
PAINT MONO (-3700 3500);
DISPLAY INVISIBLE (-3700 3500);
FORCEPROP 1 LAST BODY_TYPE PLUMBING
J 0
(-3700 3450);
DISPLAY 1.234043 (-3700 3450);
PAINT GREEN (-3700 3450);
DISPLAY INVISIBLE (-3700 3450);
FORCEPROP 1 LAST HDL_TAP TRUE
J 0
(-3375 3375);
DISPLAY 1.234043 (-3375 3375);
PAINT GREEN (-3375 3375);
DISPLAY INVISIBLE (-3375 3375);
FORCEPROP 1 LAST PATH I159
J 0
(-3700 3500);
DISPLAY 0.936170 (-3700 3500);
PAINT GREEN (-3700 3500);
DISPLAY INVISIBLE (-3700 3500);
FORCEADD PVDDQ_KLM..1
(-1300 2625);
FORCEPROP 3 LASTPIN (-1300 2575) SIG_NAME PVDDQ_KLM\g
J 0
(-1290 2585);
DISPLAY 0.659574 (-1290 2585);
PAINT MONO (-1290 2585);
DISPLAY INVISIBLE (-1290 2585);
FORCEPROP 1 LAST VOLTAGE 1.2V
J 0
(-1345 2582);
DISPLAY 0.340426 (-1345 2582);
PAINT SKYBLUE (-1345 2582);
DISPLAY INVISIBLE (-1345 2582);
FORCEPROP 2 LAST BOM_COST MEM
J 0
(-1300 2630);
PAINT ORANGE (-1300 2630);
DISPLAY INVISIBLE (-1300 2630);
FORCEPROP 2 LAST CDS_LIB mstr_symbols
J 0
(-1300 2625);
PAINT ORANGE (-1300 2625);
DISPLAY INVISIBLE (-1300 2625);
FORCEPROP 1 LAST BODY_TYPE PLUMBING
J 0
(-1345 2582);
DISPLAY 0.340426 (-1345 2582);
PAINT GREEN (-1345 2582);
DISPLAY INVISIBLE (-1345 2582);
FORCEPROP 1 LAST PATH I16
J 0
(-1250 2650);
DISPLAY 0.872340 (-1250 2650);
PAINT AQUA (-1250 2650);
DISPLAY INVISIBLE (-1250 2650);
FORCEPROP 2 LAST ROOM DDR4_CH_C
J 0
(-1300 2725);
DISPLAY 0.787234 (-1300 2725);
PAINT ORANGE (-1300 2725);
DISPLAY INVISIBLE (-1300 2725);
FORCEPROP 1 LAST HDL_POWER PVDDQ_KLM
J 1
(-1300 2675);
DISPLAY 0.872340 (-1300 2675);
PAINT GREEN (-1300 2675);
DISPLAY INVISIBLE (-1300 2675);
FORCEADD OFFPAGE..1
(-3850 3400);
FORCEPROP 2 LAST $XR0 60 
J 0
(-4101 3400);
DISPLAY 0.638298 (-4101 3400);
PAINT MONO (-4101 3400);
FORCEPROP 2 LAST $XR1 84 
J 0
(-4191 3400);
DISPLAY 0.638298 (-4191 3400);
PAINT MONO (-4191 3400);
FORCEPROP 2 LAST CDS_LIB mstr_standard
J 0
(-3850 3400);
DISPLAY 0.787234 (-3850 3400);
PAINT MONO (-3850 3400);
DISPLAY INVISIBLE (-3850 3400);
FORCEPROP 1 LAST OFFPAGE TRUE
J 0
(-3525 3275);
DISPLAY 0.936170 (-3525 3275);
PAINT GREEN (-3525 3275);
DISPLAY INVISIBLE (-3525 3275);
FORCEPROP 1 LAST COMMENT_BODY TRUE
J 0
(-3725 3300);
DISPLAY 0.936170 (-3725 3300);
PAINT GREEN (-3725 3300);
DISPLAY INVISIBLE (-3725 3300);
FORCEPROP 2 LAST PATH I160
J 0
(-3800 3475);
DISPLAY 0.787234 (-3800 3475);
PAINT MONO (-3800 3475);
DISPLAY INVISIBLE (-3800 3475);
FORCEADD OFFPAGE..1
(-3850 3000);
FORCEPROP 2 LAST $XR0 60 
J 0
(-4101 3000);
DISPLAY 0.638298 (-4101 3000);
PAINT MONO (-4101 3000);
FORCEPROP 2 LAST $XR1 84 
J 0
(-4191 3000);
DISPLAY 0.638298 (-4191 3000);
PAINT MONO (-4191 3000);
FORCEPROP 2 LAST CDS_LIB mstr_standard
J 0
(-3850 3000);
DISPLAY 0.787234 (-3850 3000);
PAINT MONO (-3850 3000);
DISPLAY INVISIBLE (-3850 3000);
FORCEPROP 1 LAST OFFPAGE TRUE
J 0
(-3525 2875);
DISPLAY 0.936170 (-3525 2875);
PAINT GREEN (-3525 2875);
DISPLAY INVISIBLE (-3525 2875);
FORCEPROP 1 LAST COMMENT_BODY TRUE
J 0
(-3725 2900);
DISPLAY 0.936170 (-3725 2900);
PAINT GREEN (-3725 2900);
DISPLAY INVISIBLE (-3725 2900);
FORCEPROP 2 LAST PATH I161
J 0
(-3800 3075);
DISPLAY 0.787234 (-3800 3075);
PAINT MONO (-3800 3075);
DISPLAY INVISIBLE (-3800 3075);
FORCEADD OFFPAGE..1
(-3850 3150);
FORCEPROP 2 LAST $XR0 60 
J 0
(-4101 3150);
DISPLAY 0.638298 (-4101 3150);
PAINT MONO (-4101 3150);
FORCEPROP 2 LAST $XR1 84 
J 0
(-4191 3150);
DISPLAY 0.638298 (-4191 3150);
PAINT MONO (-4191 3150);
FORCEPROP 2 LAST CDS_LIB mstr_standard
J 0
(-3850 3150);
DISPLAY 0.787234 (-3850 3150);
PAINT MONO (-3850 3150);
DISPLAY INVISIBLE (-3850 3150);
FORCEPROP 1 LAST OFFPAGE TRUE
J 0
(-3525 3025);
DISPLAY 0.936170 (-3525 3025);
PAINT GREEN (-3525 3025);
DISPLAY INVISIBLE (-3525 3025);
FORCEPROP 1 LAST COMMENT_BODY TRUE
J 0
(-3725 3050);
DISPLAY 0.936170 (-3725 3050);
PAINT GREEN (-3725 3050);
DISPLAY INVISIBLE (-3725 3050);
FORCEPROP 2 LAST PATH I162
J 0
(-3800 3225);
DISPLAY 0.787234 (-3800 3225);
PAINT MONO (-3800 3225);
DISPLAY INVISIBLE (-3800 3225);
FORCEADD TAP..6
(-3200 3250);
FORCEPROP 3 LASTPIN (-3150 3250) SIG_NAME M_K_CS_N<1>
J 0
(-3140 3260);
DISPLAY 0.659574 (-3140 3260);
PAINT MONO (-3140 3260);
DISPLAY INVISIBLE (-3140 3260);
FORCEPROP 1 LASTPIN (-3150 3250) BN 1
J 0
(-3200 3260);
DISPLAY 0.617021 (-3200 3260);
PAINT PINK (-3200 3260);
FORCEPROP 2 LAST CDS_LIB mstr_standard
J 0
(-3200 3250);
DISPLAY 0.787234 (-3200 3250);
PAINT MONO (-3200 3250);
DISPLAY INVISIBLE (-3200 3250);
FORCEPROP 1 LAST BODY_TYPE PLUMBING
J 0
(-3200 3200);
DISPLAY 1.234043 (-3200 3200);
PAINT GREEN (-3200 3200);
DISPLAY INVISIBLE (-3200 3200);
FORCEPROP 1 LAST HDL_TAP TRUE
J 0
(-2875 3125);
DISPLAY 1.234043 (-2875 3125);
PAINT GREEN (-2875 3125);
DISPLAY INVISIBLE (-2875 3125);
FORCEPROP 1 LAST PATH I163
J 0
(-3200 3250);
DISPLAY 0.936170 (-3200 3250);
PAINT GREEN (-3200 3250);
DISPLAY INVISIBLE (-3200 3250);
FORCEADD TAP..6
(-3200 3200);
FORCEPROP 3 LASTPIN (-3150 3200) SIG_NAME M_K_CS_N<0>
J 0
(-3140 3210);
DISPLAY 0.659574 (-3140 3210);
PAINT MONO (-3140 3210);
DISPLAY INVISIBLE (-3140 3210);
FORCEPROP 1 LASTPIN (-3150 3200) BN 0
J 0
(-3200 3210);
DISPLAY 0.617021 (-3200 3210);
PAINT PINK (-3200 3210);
FORCEPROP 2 LAST CDS_LIB mstr_standard
J 0
(-3200 3200);
DISPLAY 0.787234 (-3200 3200);
PAINT MONO (-3200 3200);
DISPLAY INVISIBLE (-3200 3200);
FORCEPROP 1 LAST BODY_TYPE PLUMBING
J 0
(-3200 3150);
DISPLAY 1.234043 (-3200 3150);
PAINT GREEN (-3200 3150);
DISPLAY INVISIBLE (-3200 3150);
FORCEPROP 1 LAST HDL_TAP TRUE
J 0
(-2875 3075);
DISPLAY 1.234043 (-2875 3075);
PAINT GREEN (-2875 3075);
DISPLAY INVISIBLE (-2875 3075);
FORCEPROP 1 LAST PATH I164
J 0
(-3200 3200);
DISPLAY 0.936170 (-3200 3200);
PAINT GREEN (-3200 3200);
DISPLAY INVISIBLE (-3200 3200);
FORCEADD TAP..6
(-3200 3100);
FORCEPROP 3 LASTPIN (-3150 3100) SIG_NAME M_K_CKE<1>
J 0
(-3140 3110);
DISPLAY 0.659574 (-3140 3110);
PAINT MONO (-3140 3110);
DISPLAY INVISIBLE (-3140 3110);
FORCEPROP 1 LASTPIN (-3150 3100) BN 1
J 0
(-3200 3110);
DISPLAY 0.617021 (-3200 3110);
PAINT PINK (-3200 3110);
FORCEPROP 2 LAST CDS_LIB mstr_standard
J 0
(-3200 3100);
DISPLAY 0.787234 (-3200 3100);
PAINT MONO (-3200 3100);
DISPLAY INVISIBLE (-3200 3100);
FORCEPROP 1 LAST BODY_TYPE PLUMBING
J 0
(-3200 3050);
DISPLAY 1.234043 (-3200 3050);
PAINT GREEN (-3200 3050);
DISPLAY INVISIBLE (-3200 3050);
FORCEPROP 1 LAST HDL_TAP TRUE
J 0
(-2875 2975);
DISPLAY 1.234043 (-2875 2975);
PAINT GREEN (-2875 2975);
DISPLAY INVISIBLE (-2875 2975);
FORCEPROP 1 LAST PATH I165
J 0
(-3200 3100);
DISPLAY 0.936170 (-3200 3100);
PAINT GREEN (-3200 3100);
DISPLAY INVISIBLE (-3200 3100);
FORCEADD TAP..6
(-3200 2950);
FORCEPROP 3 LASTPIN (-3150 2950) SIG_NAME M_K_ODT<1>
J 0
(-3140 2960);
DISPLAY 0.659574 (-3140 2960);
PAINT MONO (-3140 2960);
DISPLAY INVISIBLE (-3140 2960);
FORCEPROP 1 LASTPIN (-3150 2950) BN 1
J 0
(-3200 2960);
DISPLAY 0.617021 (-3200 2960);
PAINT PINK (-3200 2960);
FORCEPROP 2 LAST CDS_LIB mstr_standard
J 0
(-3200 2950);
DISPLAY 0.787234 (-3200 2950);
PAINT MONO (-3200 2950);
DISPLAY INVISIBLE (-3200 2950);
FORCEPROP 1 LAST BODY_TYPE PLUMBING
J 0
(-3200 2900);
DISPLAY 1.234043 (-3200 2900);
PAINT GREEN (-3200 2900);
DISPLAY INVISIBLE (-3200 2900);
FORCEPROP 1 LAST HDL_TAP TRUE
J 0
(-2875 2825);
DISPLAY 1.234043 (-2875 2825);
PAINT GREEN (-2875 2825);
DISPLAY INVISIBLE (-2875 2825);
FORCEPROP 1 LAST PATH I166
J 0
(-3200 2950);
DISPLAY 0.936170 (-3200 2950);
PAINT GREEN (-3200 2950);
DISPLAY INVISIBLE (-3200 2950);
FORCEADD SCONN288_H44441004..4
(-150 2100);
FORCEPROP 1 LAST LOCATION J1B1
J 0
(-600 3200);
DISPLAY 0.617021 (-600 3200);
PAINT AQUA (-600 3200);
FORCEPROP 1 LAST PART_NUMBER H44441-004
J 0
(-600 1050);
DISPLAY 0.617021 (-600 1050);
PAINT BLUE (-600 1050);
FORCEPROP 1 LAST MATERIAL SCONN
J 0
(-600 3150);
DISPLAY 0.617021 (-600 3150);
PAINT SKYBLUE (-600 3150);
FORCEPROP 2 LASTPIN (-650 2650) $PN 77
J 2
(-660 2660);
DISPLAY 0.617021 (-660 2660);
PAINT ORANGE (-660 2660);
FORCEPROP 2 LASTPIN (-650 2600) $PN 221
J 2
(-660 2610);
DISPLAY 0.617021 (-660 2610);
PAINT ORANGE (-660 2610);
FORCEPROP 2 LASTPIN (-650 2950) $PN 142
J 2
(-660 2960);
DISPLAY 0.617021 (-660 2960);
PAINT ORANGE (-660 2960);
FORCEPROP 2 LASTPIN (-650 2900) $PN 143
J 2
(-660 2910);
DISPLAY 0.617021 (-660 2910);
PAINT ORANGE (-660 2910);
FORCEPROP 2 LASTPIN (-650 2850) $PN 288
J 2
(-660 2860);
DISPLAY 0.617021 (-660 2860);
PAINT ORANGE (-660 2860);
FORCEPROP 2 LASTPIN (-650 2800) $PN 286
J 2
(-660 2810);
DISPLAY 0.617021 (-660 2810);
PAINT ORANGE (-660 2810);
FORCEPROP 2 LASTPIN (-650 2750) $PN 287
J 2
(-660 2760);
DISPLAY 0.617021 (-660 2760);
PAINT ORANGE (-660 2760);
FORCEPROP 2 LASTPIN (-650 2500) $PN 59
J 2
(-660 2510);
DISPLAY 0.617021 (-660 2510);
PAINT ORANGE (-660 2510);
FORCEPROP 2 LASTPIN (-650 2450) $PN 61
J 2
(-660 2460);
DISPLAY 0.617021 (-660 2460);
PAINT ORANGE (-660 2460);
FORCEPROP 2 LASTPIN (-650 2400) $PN 64
J 2
(-660 2410);
DISPLAY 0.617021 (-660 2410);
PAINT ORANGE (-660 2410);
FORCEPROP 2 LASTPIN (-650 2350) $PN 67
J 2
(-660 2360);
DISPLAY 0.617021 (-660 2360);
PAINT ORANGE (-660 2360);
FORCEPROP 2 LASTPIN (-650 2300) $PN 70
J 2
(-660 2310);
DISPLAY 0.617021 (-660 2310);
PAINT ORANGE (-660 2310);
FORCEPROP 2 LASTPIN (-650 2250) $PN 73
J 2
(-660 2260);
DISPLAY 0.617021 (-660 2260);
PAINT ORANGE (-660 2260);
FORCEPROP 2 LASTPIN (-650 2200) $PN 76
J 2
(-660 2210);
DISPLAY 0.617021 (-660 2210);
PAINT ORANGE (-660 2210);
FORCEPROP 2 LASTPIN (-650 2150) $PN 80
J 2
(-660 2160);
DISPLAY 0.617021 (-660 2160);
PAINT ORANGE (-660 2160);
FORCEPROP 2 LASTPIN (-650 2100) $PN 83
J 2
(-660 2110);
DISPLAY 0.617021 (-660 2110);
PAINT ORANGE (-660 2110);
FORCEPROP 2 LASTPIN (-650 2050) $PN 85
J 2
(-660 2060);
DISPLAY 0.617021 (-660 2060);
PAINT ORANGE (-660 2060);
FORCEPROP 2 LASTPIN (-650 2000) $PN 88
J 2
(-660 2010);
DISPLAY 0.617021 (-660 2010);
PAINT ORANGE (-660 2010);
FORCEPROP 2 LASTPIN (-650 1950) $PN 90
J 2
(-660 1960);
DISPLAY 0.617021 (-660 1960);
PAINT ORANGE (-660 1960);
FORCEPROP 2 LASTPIN (-650 1900) $PN 92
J 2
(-660 1910);
DISPLAY 0.617021 (-660 1910);
PAINT ORANGE (-660 1910);
FORCEPROP 2 LASTPIN (-650 1850) $PN 204
J 2
(-660 1860);
DISPLAY 0.617021 (-660 1860);
PAINT ORANGE (-660 1860);
FORCEPROP 2 LASTPIN (-650 1800) $PN 206
J 2
(-660 1810);
DISPLAY 0.617021 (-660 1810);
PAINT ORANGE (-660 1810);
FORCEPROP 2 LASTPIN (-650 1750) $PN 209
J 2
(-660 1760);
DISPLAY 0.617021 (-660 1760);
PAINT ORANGE (-660 1760);
FORCEPROP 2 LASTPIN (-650 1700) $PN 212
J 2
(-660 1710);
DISPLAY 0.617021 (-660 1710);
PAINT ORANGE (-660 1710);
FORCEPROP 2 LASTPIN (-650 1650) $PN 215
J 2
(-660 1660);
DISPLAY 0.617021 (-660 1660);
PAINT ORANGE (-660 1660);
FORCEPROP 2 LASTPIN (-650 1600) $PN 217
J 2
(-660 1610);
DISPLAY 0.617021 (-660 1610);
PAINT ORANGE (-660 1610);
FORCEPROP 2 LASTPIN (-650 1550) $PN 220
J 2
(-660 1560);
DISPLAY 0.617021 (-660 1560);
PAINT ORANGE (-660 1560);
FORCEPROP 2 LASTPIN (-650 1500) $PN 223
J 2
(-660 1510);
DISPLAY 0.617021 (-660 1510);
PAINT ORANGE (-660 1510);
FORCEPROP 2 LASTPIN (-650 1450) $PN 226
J 2
(-660 1460);
DISPLAY 0.617021 (-660 1460);
PAINT ORANGE (-660 1460);
FORCEPROP 2 LASTPIN (-650 1400) $PN 229
J 2
(-660 1410);
DISPLAY 0.617021 (-660 1410);
PAINT ORANGE (-660 1410);
FORCEPROP 2 LASTPIN (-650 1350) $PN 231
J 2
(-660 1360);
DISPLAY 0.617021 (-660 1360);
PAINT ORANGE (-660 1360);
FORCEPROP 2 LASTPIN (-650 1300) $PN 233
J 2
(-660 1310);
DISPLAY 0.617021 (-660 1310);
PAINT ORANGE (-660 1310);
FORCEPROP 2 LASTPIN (-650 1250) $PN 236
J 2
(-660 1260);
DISPLAY 0.617021 (-660 1260);
PAINT ORANGE (-660 1260);
FORCEPROP 2 LASTPIN (350 2950) $PN 1
J 0
(360 2960);
DISPLAY 0.617021 (360 2960);
PAINT ORANGE (360 2960);
FORCEPROP 2 LASTPIN (350 2900) $PN 145
J 0
(360 2910);
DISPLAY 0.617021 (360 2910);
PAINT ORANGE (360 2910);
FORCEPROP 1 LAST PACK_TYPE PIP
J 0
(-600 3250);
PAINT SKYBLUE (-600 3250);
DISPLAY INVISIBLE (-600 3250);
FORCEPROP 2 LAST BOM_COST MEM
J 0
(-150 2100);
PAINT ORANGE (-150 2100);
DISPLAY INVISIBLE (-150 2100);
FORCEPROP 2 LAST CDS_LIB mstr_sconn
J 0
(-150 2100);
PAINT ORANGE (-150 2100);
DISPLAY INVISIBLE (-150 2100);
FORCEPROP 2 LAST SEC_TYPE PIP
J 0
(-600 3250);
DISPLAY 1.021277 (-600 3250);
PAINT ORANGE (-600 3250);
DISPLAY INVISIBLE (-600 3250);
FORCEPROP 2 LAST SEC 4
J 0
(-600 3250);
DISPLAY 0.680851 (-600 3250);
PAINT MONO (-600 3250);
DISPLAY INVISIBLE (-600 3250);
FORCEPROP 2 LAST CDS_LOCATION J1B1
J 0
(-600 3200);
DISPLAY 0.617021 (-600 3200);
PAINT AQUA (-600 3200);
DISPLAY INVISIBLE (-600 3200);
FORCEPROP 1 LAST PATH I167
J 0
(-150 3150);
PAINT GREEN (-150 3150);
DISPLAY INVISIBLE (-150 3150);
FORCEPROP 2 LAST ROOM DDR4_CH_K
J 0
(-150 2100);
PAINT ORANGE (-150 2100);
DISPLAY INVISIBLE (-150 2100);
FORCEADD GND..1
R 2
(2500 1100);
FORCEPROP 3 LASTPIN (2500 1150) SIG_NAME GND\g
J 0
(2510 1160);
DISPLAY 0.659574 (2510 1160);
PAINT MONO (2510 1160);
DISPLAY INVISIBLE (2510 1160);
FORCEPROP 1 LAST VOLTAGE 0
J 0
(2500 1100);
PAINT SKYBLUE (2500 1100);
DISPLAY INVISIBLE (2500 1100);
FORCEPROP 2 LAST BOM_COST MEM
J 0
(2500 1105);
PAINT ORANGE (2500 1105);
DISPLAY INVISIBLE (2500 1105);
FORCEPROP 1 LAST SIZE 1B
J 2
(2425 1050);
DISPLAY 1.170213 (2425 1050);
PAINT GREEN (2425 1050);
DISPLAY INVISIBLE (2425 1050);
FORCEPROP 2 LAST CDS_LIB mstr_symbols
J 0
(2500 1100);
DISPLAY 0.787234 (2500 1100);
PAINT MONO (2500 1100);
DISPLAY INVISIBLE (2500 1100);
FORCEPROP 1 LAST BODY_TYPE PLUMBING
J 2
(2545 1057);
DISPLAY 0.340426 (2545 1057);
PAINT GREEN (2545 1057);
DISPLAY INVISIBLE (2545 1057);
FORCEPROP 1 LAST PATH I168
J 2
(2425 1100);
DISPLAY 1.404255 (2425 1100);
PAINT GREEN (2425 1100);
DISPLAY INVISIBLE (2425 1100);
FORCEPROP 2 LAST ROOM DDR4_CH_C
J 0
(2500 1105);
PAINT ORANGE (2500 1105);
DISPLAY INVISIBLE (2500 1105);
FORCEPROP 1 LAST HDL_POWER GND
J 2
(2500 1250);
DISPLAY 0.553191 (2500 1250);
PAINT GREEN (2500 1250);
DISPLAY INVISIBLE (2500 1250);
FORCEADD OFFPAGE..6
(-3800 1850);
FORCEPROP 2 LAST $XR0 84 
J 0
(-4049 1850);
DISPLAY 0.638298 (-4049 1850);
PAINT MONO (-4049 1850);
FORCEPROP 2 LAST $XR1 85 
J 0
(-4139 1850);
DISPLAY 0.638298 (-4139 1850);
PAINT MONO (-4139 1850);
FORCEPROP 2 LAST $XR2 86 
J 0
(-4229 1850);
DISPLAY 0.638298 (-4229 1850);
PAINT MONO (-4229 1850);
FORCEPROP 2 LAST $XR3 87 
J 0
(-4319 1850);
DISPLAY 0.638298 (-4319 1850);
PAINT MONO (-4319 1850);
FORCEPROP 2 LAST $XR4 88 
J 0
(-4409 1850);
DISPLAY 0.638298 (-4409 1850);
PAINT MONO (-4409 1850);
FORCEPROP 2 LAST $XR5 99 
J 0
(-4499 1850);
DISPLAY 0.638298 (-4499 1850);
PAINT MONO (-4499 1850);
FORCEPROP 2 LASTPIN (-3750 1850) SIG_NAME SMB_DDR_KLM_VPP_SDA
J 0
(-3710 1860);
DISPLAY 0.617021 (-3710 1860);
PAINT ORANGE (-3710 1860);
FORCEPROP 2 LAST CDS_LIB mstr_standard
J 0
(-3800 1850);
DISPLAY 0.787234 (-3800 1850);
PAINT MONO (-3800 1850);
DISPLAY INVISIBLE (-3800 1850);
FORCEPROP 1 LAST OFFPAGE TRUE
J 0
(-3475 1725);
DISPLAY 0.936170 (-3475 1725);
PAINT GREEN (-3475 1725);
DISPLAY INVISIBLE (-3475 1725);
FORCEPROP 1 LAST COMMENT_BODY TRUE
J 0
(-3700 1775);
DISPLAY 0.936170 (-3700 1775);
PAINT GREEN (-3700 1775);
DISPLAY INVISIBLE (-3700 1775);
FORCEPROP 2 LAST PATH I169
J 0
(-4100 1900);
DISPLAY 0.787234 (-4100 1900);
PAINT ORANGE (-4100 1900);
DISPLAY INVISIBLE (-4100 1900);
FORCEADD PVTT_KLM..1
(-1050 2800);
FORCEPROP 3 LASTPIN (-1050 2750) SIG_NAME PVTT_KLM\g
J 0
(-1040 2760);
DISPLAY 0.659574 (-1040 2760);
PAINT MONO (-1040 2760);
DISPLAY INVISIBLE (-1040 2760);
FORCEPROP 1 LAST VOLTAGE 0.6V
J 0
(-1095 2757);
DISPLAY 0.340426 (-1095 2757);
PAINT SKYBLUE (-1095 2757);
DISPLAY INVISIBLE (-1095 2757);
FORCEPROP 2 LAST BOM_COST MEM
J 0
(-1050 2805);
PAINT ORANGE (-1050 2805);
DISPLAY INVISIBLE (-1050 2805);
FORCEPROP 2 LAST CDS_LIB mstr_symbols
J 0
(-1050 2800);
PAINT ORANGE (-1050 2800);
DISPLAY INVISIBLE (-1050 2800);
FORCEPROP 1 LAST BODY_TYPE PLUMBING
J 0
(-1095 2757);
DISPLAY 0.340426 (-1095 2757);
PAINT GREEN (-1095 2757);
DISPLAY INVISIBLE (-1095 2757);
FORCEPROP 1 LAST PATH I17
J 0
(-1000 2825);
DISPLAY 0.872340 (-1000 2825);
PAINT AQUA (-1000 2825);
DISPLAY INVISIBLE (-1000 2825);
FORCEPROP 2 LAST ROOM DDR4_CH_C
J 0
(-1050 2900);
DISPLAY 0.787234 (-1050 2900);
PAINT ORANGE (-1050 2900);
DISPLAY INVISIBLE (-1050 2900);
FORCEPROP 1 LAST HDL_POWER PVTT_KLM
J 1
(-1050 2850);
DISPLAY 0.872340 (-1050 2850);
PAINT GREEN (-1050 2850);
DISPLAY INVISIBLE (-1050 2850);
FORCEADD OFFPAGE..1
(-3800 1800);
FORCEPROP 2 LAST $XR0 99 
J 0
(-4051 1800);
DISPLAY 0.638298 (-4051 1800);
PAINT MONO (-4051 1800);
FORCEPROP 2 LAST $XR1 84 
J 0
(-4141 1800);
DISPLAY 0.638298 (-4141 1800);
PAINT MONO (-4141 1800);
FORCEPROP 2 LAST $XR2 85 
J 0
(-4231 1800);
DISPLAY 0.638298 (-4231 1800);
PAINT MONO (-4231 1800);
FORCEPROP 2 LAST $XR3 86 
J 0
(-4321 1800);
DISPLAY 0.638298 (-4321 1800);
PAINT MONO (-4321 1800);
FORCEPROP 2 LAST $XR4 87 
J 0
(-4411 1800);
DISPLAY 0.638298 (-4411 1800);
PAINT MONO (-4411 1800);
FORCEPROP 2 LAST $XR5 88 
J 0
(-4501 1800);
DISPLAY 0.638298 (-4501 1800);
PAINT MONO (-4501 1800);
FORCEPROP 2 LAST CDS_LIB mstr_standard
J 0
(-3800 1800);
DISPLAY 0.787234 (-3800 1800);
PAINT MONO (-3800 1800);
DISPLAY INVISIBLE (-3800 1800);
FORCEPROP 1 LAST OFFPAGE TRUE
J 0
(-3475 1675);
DISPLAY 0.936170 (-3475 1675);
PAINT GREEN (-3475 1675);
DISPLAY INVISIBLE (-3475 1675);
FORCEPROP 1 LAST COMMENT_BODY TRUE
J 0
(-3675 1700);
DISPLAY 0.936170 (-3675 1700);
PAINT GREEN (-3675 1700);
DISPLAY INVISIBLE (-3675 1700);
FORCEPROP 2 LAST PATH I170
J 0
(-4075 1850);
DISPLAY 0.787234 (-4075 1850);
PAINT ORANGE (-4075 1850);
DISPLAY INVISIBLE (-4075 1850);
FORCEADD OFFPAGE..1
(-4750 1700);
FORCEPROP 2 LAST $XR0 100 
J 0
(-5002 1700);
DISPLAY 0.638298 (-5002 1700);
PAINT MONO (-5002 1700);
FORCEPROP 2 LAST $XR1 84 
J 0
(-5092 1700);
DISPLAY 0.638298 (-5092 1700);
PAINT MONO (-5092 1700);
FORCEPROP 2 LAST CDS_LIB mstr_standard
J 0
(-4750 1700);
DISPLAY 0.787234 (-4750 1700);
PAINT MONO (-4750 1700);
DISPLAY INVISIBLE (-4750 1700);
FORCEPROP 1 LAST OFFPAGE TRUE
J 0
(-4425 1575);
DISPLAY 0.936170 (-4425 1575);
PAINT GREEN (-4425 1575);
DISPLAY INVISIBLE (-4425 1575);
FORCEPROP 1 LAST COMMENT_BODY TRUE
J 0
(-4625 1600);
DISPLAY 0.936170 (-4625 1600);
PAINT GREEN (-4625 1600);
DISPLAY INVISIBLE (-4625 1600);
FORCEPROP 2 LAST PATH I171
J 0
(-5000 1750);
DISPLAY 0.787234 (-5000 1750);
PAINT ORANGE (-5000 1750);
DISPLAY INVISIBLE (-5000 1750);
FORCEADD GND..1
R 2
(-5100 1850);
FORCEPROP 3 LASTPIN (-5100 1900) SIG_NAME GND\g
J 0
(-5090 1910);
DISPLAY 0.659574 (-5090 1910);
PAINT MONO (-5090 1910);
DISPLAY INVISIBLE (-5090 1910);
FORCEPROP 1 LAST VOLTAGE 0
J 0
(-5100 1850);
PAINT SKYBLUE (-5100 1850);
DISPLAY INVISIBLE (-5100 1850);
FORCEPROP 2 LAST BOM_COST MEM
J 0
(-5100 1855);
PAINT ORANGE (-5100 1855);
DISPLAY INVISIBLE (-5100 1855);
FORCEPROP 2 LAST CDS_LIB mstr_symbols
J 0
(-5100 1850);
DISPLAY 0.787234 (-5100 1850);
PAINT MONO (-5100 1850);
DISPLAY INVISIBLE (-5100 1850);
FORCEPROP 1 LAST SIZE 1B
J 2
(-5175 1800);
DISPLAY 1.170213 (-5175 1800);
PAINT GREEN (-5175 1800);
DISPLAY INVISIBLE (-5175 1800);
FORCEPROP 1 LAST BODY_TYPE PLUMBING
J 2
(-5055 1807);
DISPLAY 0.340426 (-5055 1807);
PAINT GREEN (-5055 1807);
DISPLAY INVISIBLE (-5055 1807);
FORCEPROP 1 LAST PATH I173
J 2
(-5175 1850);
DISPLAY 1.404255 (-5175 1850);
PAINT GREEN (-5175 1850);
DISPLAY INVISIBLE (-5175 1850);
FORCEPROP 2 LAST ROOM DDR4_CH_C
J 0
(-5100 1855);
PAINT ORANGE (-5100 1855);
DISPLAY INVISIBLE (-5100 1855);
FORCEPROP 1 LAST HDL_POWER GND
J 2
(-5100 2000);
DISPLAY 0.553191 (-5100 2000);
PAINT GREEN (-5100 2000);
DISPLAY INVISIBLE (-5100 2000);
FORCEADD OFFPAGE..5
(-4175 2550);
FORCEPROP 2 LAST $XR0 43 
J 0
(-4429 2550);
DISPLAY 0.638298 (-4429 2550);
PAINT MONO (-4429 2550);
FORCEPROP 2 LAST $XR1 44 
J 0
(-4519 2550);
DISPLAY 0.638298 (-4519 2550);
PAINT MONO (-4519 2550);
FORCEPROP 2 LAST $XR2 45 
J 0
(-4609 2550);
DISPLAY 0.638298 (-4609 2550);
PAINT MONO (-4609 2550);
FORCEPROP 2 LAST $XR3 46 
J 0
(-4699 2550);
DISPLAY 0.638298 (-4699 2550);
PAINT MONO (-4699 2550);
FORCEPROP 2 LAST $XR4 47 
J 0
(-4789 2550);
DISPLAY 0.638298 (-4789 2550);
PAINT MONO (-4789 2550);
FORCEPROP 2 LAST $XR5 48 
J 0
(-4879 2550);
DISPLAY 0.638298 (-4879 2550);
PAINT MONO (-4879 2550);
FORCEPROP 2 LAST $XR6 49 
J 0
(-4969 2550);
DISPLAY 0.638298 (-4969 2550);
PAINT MONO (-4969 2550);
FORCEPROP 2 LAST $XR7 50 
J 0
(-5059 2550);
DISPLAY 0.638298 (-5059 2550);
PAINT MONO (-5059 2550);
FORCEPROP 2 LAST $XR8 51 
J 0
(-5149 2550);
DISPLAY 0.638298 (-5149 2550);
PAINT MONO (-5149 2550);
FORCEPROP 2 LAST $XR9 52 
J 0
(-5239 2550);
DISPLAY 0.638298 (-5239 2550);
PAINT MONO (-5239 2550);
FORCEPROP 2 LAST $XR10 53 
J 0
(-4429 2514);
DISPLAY 0.638298 (-4429 2514);
PAINT MONO (-4429 2514);
FORCEPROP 2 LAST $XR11 54 
J 0
(-4519 2514);
DISPLAY 0.638298 (-4519 2514);
PAINT MONO (-4519 2514);
FORCEPROP 2 LAST $XR12 77 
J 0
(-4609 2514);
DISPLAY 0.638298 (-4609 2514);
PAINT MONO (-4609 2514);
FORCEPROP 2 LAST $XR13 78 
J 0
(-4699 2514);
DISPLAY 0.638298 (-4699 2514);
PAINT MONO (-4699 2514);
FORCEPROP 2 LAST $XR14 79 
J 0
(-4789 2514);
DISPLAY 0.638298 (-4789 2514);
PAINT MONO (-4789 2514);
FORCEPROP 2 LAST $XR15 80 
J 0
(-4879 2514);
DISPLAY 0.638298 (-4879 2514);
PAINT MONO (-4879 2514);
FORCEPROP 2 LAST $XR16 81 
J 0
(-4969 2514);
DISPLAY 0.638298 (-4969 2514);
PAINT MONO (-4969 2514);
FORCEPROP 2 LAST $XR17 82 
J 0
(-5059 2514);
DISPLAY 0.638298 (-5059 2514);
PAINT MONO (-5059 2514);
FORCEPROP 2 LAST $XR18 84 
J 0
(-5149 2514);
DISPLAY 0.638298 (-5149 2514);
PAINT MONO (-5149 2514);
FORCEPROP 2 LAST $XR19 85 
J 0
(-4429 2586);
DISPLAY 0.638298 (-4429 2586);
PAINT MONO (-4429 2586);
FORCEPROP 2 LAST $XR20 86 
J 0
(-4519 2586);
DISPLAY 0.638298 (-4519 2586);
PAINT MONO (-4519 2586);
FORCEPROP 2 LAST $XR21 87 
J 0
(-4609 2586);
DISPLAY 0.638298 (-4609 2586);
PAINT MONO (-4609 2586);
FORCEPROP 2 LAST $XR22 88 
J 0
(-4699 2586);
DISPLAY 0.638298 (-4699 2586);
PAINT MONO (-4699 2586);
FORCEPROP 2 LAST $XR23 94 
J 0
(-4789 2586);
DISPLAY 0.638298 (-4789 2586);
PAINT MONO (-4789 2586);
FORCEPROP 2 LAST CDS_LIB mstr_standard
J 0
(-4175 2550);
DISPLAY 0.787234 (-4175 2550);
PAINT MONO (-4175 2550);
DISPLAY INVISIBLE (-4175 2550);
FORCEPROP 1 LAST OFFPAGE TRUE
J 0
(-3850 2425);
DISPLAY 1.404255 (-3850 2425);
PAINT GREEN (-3850 2425);
DISPLAY INVISIBLE (-3850 2425);
FORCEPROP 1 LAST COMMENT_BODY TRUE
J 0
(-4075 2475);
DISPLAY 1.404255 (-4075 2475);
PAINT GREEN (-4075 2475);
DISPLAY INVISIBLE (-4075 2475);
FORCEPROP 2 LAST PATH I174
J 0
(-4125 2625);
DISPLAY 0.787234 (-4125 2625);
PAINT ORANGE (-4125 2625);
DISPLAY INVISIBLE (-4125 2625);
FORCEADD GND..1
(-4600 1250);
FORCEPROP 3 LASTPIN (-4600 1300) SIG_NAME GND\g
J 0
(-4590 1310);
DISPLAY 0.659574 (-4590 1310);
PAINT MONO (-4590 1310);
DISPLAY INVISIBLE (-4590 1310);
FORCEPROP 1 LAST VOLTAGE 0
J 0
(-4600 1250);
PAINT SKYBLUE (-4600 1250);
DISPLAY INVISIBLE (-4600 1250);
FORCEPROP 2 LAST BOM_COST MEM
J 0
(-4600 1255);
PAINT ORANGE (-4600 1255);
DISPLAY INVISIBLE (-4600 1255);
FORCEPROP 1 LAST SIZE 1B
J 0
(-4525 1200);
DISPLAY 1.787234 (-4525 1200);
PAINT GREEN (-4525 1200);
DISPLAY INVISIBLE (-4525 1200);
FORCEPROP 2 LAST CDS_LIB mstr_symbols
J 0
(-4600 1250);
PAINT ORANGE (-4600 1250);
DISPLAY INVISIBLE (-4600 1250);
FORCEPROP 1 LAST BODY_TYPE PLUMBING
J 0
(-4645 1207);
DISPLAY 0.340426 (-4645 1207);
PAINT GREEN (-4645 1207);
DISPLAY INVISIBLE (-4645 1207);
FORCEPROP 1 LAST PATH I175
J 0
(-4525 1250);
DISPLAY 1.404255 (-4525 1250);
PAINT GREEN (-4525 1250);
DISPLAY INVISIBLE (-4525 1250);
FORCEPROP 2 LAST ROOM DDR4_CH_C
J 0
(-4600 1255);
PAINT ORANGE (-4600 1255);
DISPLAY INVISIBLE (-4600 1255);
FORCEPROP 1 LAST HDL_POWER GND
J 0
(-4600 1400);
DISPLAY 1.404255 (-4600 1400);
PAINT GREEN (-4600 1400);
DISPLAY INVISIBLE (-4600 1400);
FORCEADD CAP_A..1
R 2
(-4600 1500);
FORCEPROP 1 LAST LOCATION C1B9
J 2
(-4650 1600);
DISPLAY 0.617021 (-4650 1600);
PAINT AQUA (-4650 1600);
FORCEPROP 1 LAST PART_NUMBER A36096-045
J 2
(-4650 1350);
DISPLAY 0.617021 (-4650 1350);
PAINT BLUE (-4650 1350);
FORCEPROP 1 LAST VALUE 0.01UF
J 2
(-4650 1550);
DISPLAY 0.617021 (-4650 1550);
PAINT SKYBLUE (-4650 1550);
FORCEPROP 1 LAST TOLERANCE 10%
J 2
(-4650 1450);
DISPLAY 0.617021 (-4650 1450);
PAINT SKYBLUE (-4650 1450);
FORCEPROP 1 LAST PACK_TYPE 0402V
J 2
(-4650 1300);
DISPLAY 0.617021 (-4650 1300);
PAINT SKYBLUE (-4650 1300);
FORCEPROP 1 LAST VOLTAGE 25V
J 2
(-4650 1500);
DISPLAY 0.617021 (-4650 1500);
PAINT SKYBLUE (-4650 1500);
FORCEPROP 1 LAST MATERIAL X7R
J 2
(-4650 1400);
DISPLAY 0.617021 (-4650 1400);
PAINT SKYBLUE (-4650 1400);
FORCEPROP 2 LAST CDS_LOCATION C1B9
J 2
(-4650 1600);
DISPLAY 0.617021 (-4650 1600);
PAINT AQUA (-4650 1600);
DISPLAY INVISIBLE (-4650 1600);
FORCEPROP 2 LAST BOM_COST MEM
J 0
(-4600 1500);
PAINT ORANGE (-4600 1500);
DISPLAY INVISIBLE (-4600 1500);
FORCEPROP 2 LAST CDS_LIB dev_discrete
J 0
(-4600 1500);
PAINT ORANGE (-4600 1500);
DISPLAY INVISIBLE (-4600 1500);
FORCEPROP 2 LAST CDS_SEC 1
J 2
(-4650 1700);
PAINT MONO (-4650 1700);
DISPLAY INVISIBLE (-4650 1700);
FORCEPROP 2 LAST $SEC 1
J 0
(-4650 1700);
PAINT MONO (-4650 1700);
DISPLAY INVISIBLE (-4650 1700);
FORCEPROP 1 LAST PATH I176
J 2
(-4650 1650);
DISPLAY 0.978723 (-4650 1650);
PAINT WHITE (-4650 1650);
DISPLAY INVISIBLE (-4650 1650);
FORCEPROP 2 LAST ROOM DDR4_CH_K
J 0
(-4600 1500);
PAINT ORANGE (-4600 1500);
DISPLAY INVISIBLE (-4600 1500);
FORCEPROP 1 LASTPIN (-4600 1600) $PN 1
J 2
(-4610 1580);
DISPLAY 0.787234 (-4610 1580);
PAINT ORANGE (-4610 1580);
DISPLAY INVISIBLE (-4610 1580);
FORCEPROP 1 LASTPIN (-4600 1400) $PN 2
J 2
(-4610 1380);
DISPLAY 0.787234 (-4610 1380);
PAINT ORANGE (-4610 1380);
DISPLAY INVISIBLE (-4610 1380);
FORCEADD PVPP_KLM..1
(-850 3100);
FORCEPROP 3 LASTPIN (-850 3050) SIG_NAME PVPP_KLM\g
J 0
(-840 3060);
DISPLAY 0.659574 (-840 3060);
PAINT MONO (-840 3060);
DISPLAY INVISIBLE (-840 3060);
FORCEPROP 1 LAST VOLTAGE 2.5V
J 0
(-895 3057);
DISPLAY 0.340426 (-895 3057);
PAINT SKYBLUE (-895 3057);
DISPLAY INVISIBLE (-895 3057);
FORCEPROP 0 LAST BOM_COST MEM
J 0
(-850 3200);
PAINT ORANGE (-850 3200);
DISPLAY INVISIBLE (-850 3200);
FORCEPROP 2 LAST CDS_LIB mstr_symbols
J 0
(-850 3100);
PAINT ORANGE (-850 3100);
DISPLAY INVISIBLE (-850 3100);
FORCEPROP 1 LAST BODY_TYPE PLUMBING
J 0
(-895 3057);
DISPLAY 0.340426 (-895 3057);
PAINT GREEN (-895 3057);
DISPLAY INVISIBLE (-895 3057);
FORCEPROP 1 LAST PATH I177
J 0
(-800 3125);
DISPLAY 0.872340 (-800 3125);
PAINT AQUA (-800 3125);
DISPLAY INVISIBLE (-800 3125);
FORCEPROP 2 LAST ROOM DDR4_CH_C
J 0
(-850 3200);
PAINT ORANGE (-850 3200);
DISPLAY INVISIBLE (-850 3200);
FORCEPROP 1 LAST HDL_POWER PVPP_KLM
J 1
(-850 3150);
DISPLAY 0.872340 (-850 3150);
PAINT GREEN (-850 3150);
DISPLAY INVISIBLE (-850 3150);
FORCEADD PVPP_KLM..1
(-5100 2200);
FORCEPROP 3 LASTPIN (-5100 2150) SIG_NAME PVPP_KLM\g
J 0
(-5090 2160);
DISPLAY 0.659574 (-5090 2160);
PAINT MONO (-5090 2160);
DISPLAY INVISIBLE (-5090 2160);
FORCEPROP 1 LAST VOLTAGE 2.5V
J 0
(-5145 2157);
DISPLAY 0.340426 (-5145 2157);
PAINT SKYBLUE (-5145 2157);
DISPLAY INVISIBLE (-5145 2157);
FORCEPROP 0 LAST BOM_COST MEM
J 0
(-5100 2300);
PAINT ORANGE (-5100 2300);
DISPLAY INVISIBLE (-5100 2300);
FORCEPROP 2 LAST CDS_LIB mstr_symbols
J 0
(-5100 2200);
PAINT ORANGE (-5100 2200);
DISPLAY INVISIBLE (-5100 2200);
FORCEPROP 1 LAST BODY_TYPE PLUMBING
J 0
(-5145 2157);
DISPLAY 0.340426 (-5145 2157);
PAINT GREEN (-5145 2157);
DISPLAY INVISIBLE (-5145 2157);
FORCEPROP 1 LAST PATH I178
J 0
(-5050 2225);
DISPLAY 0.872340 (-5050 2225);
PAINT AQUA (-5050 2225);
DISPLAY INVISIBLE (-5050 2225);
FORCEPROP 2 LAST ROOM DDR4_CH_C
J 0
(-5100 2300);
PAINT ORANGE (-5100 2300);
DISPLAY INVISIBLE (-5100 2300);
FORCEPROP 1 LAST HDL_POWER PVPP_KLM
J 1
(-5100 2250);
DISPLAY 0.872340 (-5100 2250);
PAINT GREEN (-5100 2250);
DISPLAY INVISIBLE (-5100 2250);
FORCEADD OFFPAGE..1
(-3850 1400);
FORCEPROP 2 LAST $XR0 89 
J 0
(-4101 1400);
DISPLAY 0.638298 (-4101 1400);
PAINT MONO (-4101 1400);
FORCEPROP 2 LAST $XR1 84 
J 0
(-4191 1400);
DISPLAY 0.638298 (-4191 1400);
PAINT MONO (-4191 1400);
FORCEPROP 2 LAST $XR2 85 
J 0
(-4281 1400);
DISPLAY 0.638298 (-4281 1400);
PAINT MONO (-4281 1400);
FORCEPROP 2 LAST $XR3 86 
J 0
(-4371 1400);
DISPLAY 0.638298 (-4371 1400);
PAINT MONO (-4371 1400);
FORCEPROP 2 LAST $XR4 87 
J 0
(-4461 1400);
DISPLAY 0.638298 (-4461 1400);
PAINT MONO (-4461 1400);
FORCEPROP 2 LAST $XR5 88 
J 0
(-4551 1400);
DISPLAY 0.638298 (-4551 1400);
PAINT MONO (-4551 1400);
FORCEPROP 2 LAST CDS_LIB mstr_standard
J 0
(-3850 1400);
PAINT ORANGE (-3850 1400);
DISPLAY INVISIBLE (-3850 1400);
FORCEPROP 1 LAST OFFPAGE TRUE
J 0
(-3525 1275);
DISPLAY 0.936170 (-3525 1275);
PAINT GREEN (-3525 1275);
DISPLAY INVISIBLE (-3525 1275);
FORCEPROP 1 LAST COMMENT_BODY TRUE
J 0
(-3725 1300);
DISPLAY 0.936170 (-3725 1300);
PAINT GREEN (-3725 1300);
DISPLAY INVISIBLE (-3725 1300);
FORCEPROP 2 LAST PATH I179
J 0
(-3800 1475);
PAINT ORANGE (-3800 1475);
DISPLAY INVISIBLE (-3800 1475);
FORCEADD TAP..6
(-3700 3600);
FORCEPROP 3 LASTPIN (-3650 3600) SIG_NAME M_K_CLK_DN<1>
J 0
(-3640 3610);
DISPLAY 0.659574 (-3640 3610);
PAINT MONO (-3640 3610);
DISPLAY INVISIBLE (-3640 3610);
FORCEPROP 1 LASTPIN (-3650 3600) BN 1
J 0
(-3702 3608);
DISPLAY 0.617021 (-3702 3608);
PAINT PINK (-3702 3608);
FORCEPROP 2 LAST CDS_LIB mstr_standard
J 0
(-3700 3600);
PAINT MONO (-3700 3600);
DISPLAY INVISIBLE (-3700 3600);
FORCEPROP 1 LAST BODY_TYPE PLUMBING
J 0
(-3700 3550);
DISPLAY 1.234043 (-3700 3550);
PAINT GREEN (-3700 3550);
DISPLAY INVISIBLE (-3700 3550);
FORCEPROP 1 LAST HDL_TAP TRUE
J 0
(-3375 3475);
DISPLAY 1.234043 (-3375 3475);
PAINT GREEN (-3375 3475);
DISPLAY INVISIBLE (-3375 3475);
FORCEPROP 1 LAST PATH I183
J 0
(-3702 3600);
DISPLAY 0.872340 (-3702 3600);
PAINT GREEN (-3702 3600);
DISPLAY INVISIBLE (-3702 3600);
FORCEADD TAP..6
(-3550 3650);
FORCEPROP 3 LASTPIN (-3500 3650) SIG_NAME M_K_CLK_DP<1>
J 0
(-3490 3660);
DISPLAY 0.659574 (-3490 3660);
PAINT MONO (-3490 3660);
DISPLAY INVISIBLE (-3490 3660);
FORCEPROP 1 LASTPIN (-3500 3650) BN 1
J 0
(-3552 3658);
DISPLAY 0.617021 (-3552 3658);
PAINT PINK (-3552 3658);
FORCEPROP 2 LAST CDS_LIB mstr_standard
J 0
(-3550 3650);
PAINT MONO (-3550 3650);
DISPLAY INVISIBLE (-3550 3650);
FORCEPROP 1 LAST BODY_TYPE PLUMBING
J 0
(-3550 3600);
DISPLAY 1.234043 (-3550 3600);
PAINT GREEN (-3550 3600);
DISPLAY INVISIBLE (-3550 3600);
FORCEPROP 1 LAST HDL_TAP TRUE
J 0
(-3225 3525);
DISPLAY 1.234043 (-3225 3525);
PAINT GREEN (-3225 3525);
DISPLAY INVISIBLE (-3225 3525);
FORCEPROP 1 LAST PATH I184
J 0
(-3552 3650);
DISPLAY 0.872340 (-3552 3650);
PAINT GREEN (-3552 3650);
DISPLAY INVISIBLE (-3552 3650);
FORCEADD P12V_NVDIMM_KLM..1
(550 3175);
FORCEPROP 3 LASTPIN (550 3125) SIG_NAME P12V_NVDIMM_KLM\g
J 0
(560 3135);
DISPLAY 0.659574 (560 3135);
PAINT MONO (560 3135);
DISPLAY INVISIBLE (560 3135);
FORCEPROP 1 LAST VOLTAGE 12.0
J 0
(505 3132);
DISPLAY 0.340426 (505 3132);
PAINT SKYBLUE (505 3132);
DISPLAY INVISIBLE (505 3132);
FORCEPROP 2 LAST CDS_LIB mstr_symbols
J 0
(550 3175);
PAINT ORANGE (550 3175);
DISPLAY INVISIBLE (550 3175);
FORCEPROP 1 LAST BODY_TYPE PLUMBING
J 0
(505 3132);
DISPLAY 0.340426 (505 3132);
PAINT GREEN (505 3132);
DISPLAY INVISIBLE (505 3132);
FORCEPROP 1 LAST PATH I185
J 0
(600 3200);
DISPLAY 0.872340 (600 3200);
PAINT AQUA (600 3200);
DISPLAY INVISIBLE (600 3200);
FORCEPROP 1 LAST HDL_POWER P12V_NVDIMM_KLM
J 1
(550 3225);
DISPLAY 0.872340 (550 3225);
PAINT GREEN (550 3225);
DISPLAY INVISIBLE (550 3225);
FORCEADD TAP..6
R 2
(900 4550);
FORCEPROP 3 LASTPIN (850 4550) SIG_NAME M_K_DQS_DN<11>
J 0
(860 4560);
DISPLAY 0.659574 (860 4560);
PAINT MONO (860 4560);
DISPLAY INVISIBLE (860 4560);
FORCEPROP 1 LASTPIN (850 4550) BN 11
J 2
(900 4560);
DISPLAY 0.617021 (900 4560);
PAINT PINK (900 4560);
FORCEPROP 2 LAST CDS_LIB mstr_standard
J 0
(900 4550);
DISPLAY 0.787234 (900 4550);
PAINT MONO (900 4550);
DISPLAY INVISIBLE (900 4550);
FORCEPROP 1 LAST BODY_TYPE PLUMBING
J 2
(900 4500);
DISPLAY 1.234043 (900 4500);
PAINT GREEN (900 4500);
DISPLAY INVISIBLE (900 4500);
FORCEPROP 1 LAST HDL_TAP TRUE
J 2
(575 4425);
DISPLAY 1.234043 (575 4425);
PAINT GREEN (575 4425);
DISPLAY INVISIBLE (575 4425);
FORCEPROP 1 LAST PATH I19
J 2
(900 4550);
DISPLAY 0.936170 (900 4550);
PAINT GREEN (900 4550);
DISPLAY INVISIBLE (900 4550);
FORCEADD OFFPAGE..3
(1600 5200);
FORCEPROP 2 LAST $XR0 60 
J 0
(1814 5200);
DISPLAY 0.638298 (1814 5200);
PAINT MONO (1814 5200);
FORCEPROP 2 LAST $XR1 84 
J 0
(1904 5200);
DISPLAY 0.638298 (1904 5200);
PAINT MONO (1904 5200);
FORCEPROP 2 LAST CDS_LIB mstr_standard
J 0
(1600 5200);
DISPLAY 0.787234 (1600 5200);
PAINT MONO (1600 5200);
DISPLAY INVISIBLE (1600 5200);
FORCEPROP 1 LAST OFFPAGE TRUE
J 0
(1925 5075);
DISPLAY 0.936170 (1925 5075);
PAINT GREEN (1925 5075);
DISPLAY INVISIBLE (1925 5075);
FORCEPROP 1 LAST COMMENT_BODY TRUE
J 0
(1550 5100);
DISPLAY 0.936170 (1550 5100);
PAINT GREEN (1550 5100);
DISPLAY INVISIBLE (1550 5100);
FORCEPROP 2 LAST PATH I2
J 0
(1800 5275);
DISPLAY 0.787234 (1800 5275);
PAINT MONO (1800 5275);
DISPLAY INVISIBLE (1800 5275);
FORCEADD TAP..6
R 2
(900 4450);
FORCEPROP 3 LASTPIN (850 4450) SIG_NAME M_K_DQS_DN<10>
J 0
(860 4460);
DISPLAY 0.659574 (860 4460);
PAINT MONO (860 4460);
DISPLAY INVISIBLE (860 4460);
FORCEPROP 1 LASTPIN (850 4450) BN 10
J 2
(900 4460);
DISPLAY 0.617021 (900 4460);
PAINT PINK (900 4460);
FORCEPROP 2 LAST CDS_LIB mstr_standard
J 0
(900 4450);
DISPLAY 0.787234 (900 4450);
PAINT MONO (900 4450);
DISPLAY INVISIBLE (900 4450);
FORCEPROP 1 LAST BODY_TYPE PLUMBING
J 2
(900 4400);
DISPLAY 1.234043 (900 4400);
PAINT GREEN (900 4400);
DISPLAY INVISIBLE (900 4400);
FORCEPROP 1 LAST HDL_TAP TRUE
J 2
(575 4325);
DISPLAY 1.234043 (575 4325);
PAINT GREEN (575 4325);
DISPLAY INVISIBLE (575 4325);
FORCEPROP 1 LAST PATH I20
J 2
(900 4450);
DISPLAY 0.936170 (900 4450);
PAINT GREEN (900 4450);
DISPLAY INVISIBLE (900 4450);
FORCEADD TAP..6
R 2
(900 4350);
FORCEPROP 3 LASTPIN (850 4350) SIG_NAME M_K_DQS_DN<9>
J 0
(860 4360);
DISPLAY 0.659574 (860 4360);
PAINT MONO (860 4360);
DISPLAY INVISIBLE (860 4360);
FORCEPROP 1 LASTPIN (850 4350) BN 9
J 2
(900 4360);
DISPLAY 0.617021 (900 4360);
PAINT PINK (900 4360);
FORCEPROP 2 LAST CDS_LIB mstr_standard
J 0
(900 4350);
DISPLAY 0.787234 (900 4350);
PAINT MONO (900 4350);
DISPLAY INVISIBLE (900 4350);
FORCEPROP 1 LAST BODY_TYPE PLUMBING
J 2
(900 4300);
DISPLAY 1.234043 (900 4300);
PAINT GREEN (900 4300);
DISPLAY INVISIBLE (900 4300);
FORCEPROP 1 LAST HDL_TAP TRUE
J 2
(575 4225);
DISPLAY 1.234043 (575 4225);
PAINT GREEN (575 4225);
DISPLAY INVISIBLE (575 4225);
FORCEPROP 1 LAST PATH I21
J 2
(900 4350);
DISPLAY 0.936170 (900 4350);
PAINT GREEN (900 4350);
DISPLAY INVISIBLE (900 4350);
FORCEADD TAP..6
R 2
(900 4250);
FORCEPROP 3 LASTPIN (850 4250) SIG_NAME M_K_DQS_DN<8>
J 0
(860 4260);
DISPLAY 0.659574 (860 4260);
PAINT MONO (860 4260);
DISPLAY INVISIBLE (860 4260);
FORCEPROP 1 LASTPIN (850 4250) BN 8
J 2
(900 4260);
DISPLAY 0.617021 (900 4260);
PAINT PINK (900 4260);
FORCEPROP 2 LAST CDS_LIB mstr_standard
J 0
(900 4250);
DISPLAY 0.787234 (900 4250);
PAINT MONO (900 4250);
DISPLAY INVISIBLE (900 4250);
FORCEPROP 1 LAST BODY_TYPE PLUMBING
J 2
(900 4200);
DISPLAY 1.234043 (900 4200);
PAINT GREEN (900 4200);
DISPLAY INVISIBLE (900 4200);
FORCEPROP 1 LAST HDL_TAP TRUE
J 2
(575 4125);
DISPLAY 1.234043 (575 4125);
PAINT GREEN (575 4125);
DISPLAY INVISIBLE (575 4125);
FORCEPROP 1 LAST PATH I22
J 2
(900 4250);
DISPLAY 0.936170 (900 4250);
PAINT GREEN (900 4250);
DISPLAY INVISIBLE (900 4250);
FORCEADD TAP..6
R 2
(900 4150);
FORCEPROP 3 LASTPIN (850 4150) SIG_NAME M_K_DQS_DN<7>
J 0
(860 4160);
DISPLAY 0.659574 (860 4160);
PAINT MONO (860 4160);
DISPLAY INVISIBLE (860 4160);
FORCEPROP 1 LASTPIN (850 4150) BN 7
J 2
(900 4160);
DISPLAY 0.617021 (900 4160);
PAINT PINK (900 4160);
FORCEPROP 2 LAST CDS_LIB mstr_standard
J 0
(900 4150);
DISPLAY 0.787234 (900 4150);
PAINT MONO (900 4150);
DISPLAY INVISIBLE (900 4150);
FORCEPROP 1 LAST BODY_TYPE PLUMBING
J 2
(900 4100);
DISPLAY 1.234043 (900 4100);
PAINT GREEN (900 4100);
DISPLAY INVISIBLE (900 4100);
FORCEPROP 1 LAST HDL_TAP TRUE
J 2
(575 4025);
DISPLAY 1.234043 (575 4025);
PAINT GREEN (575 4025);
DISPLAY INVISIBLE (575 4025);
FORCEPROP 1 LAST PATH I23
J 2
(900 4150);
DISPLAY 0.936170 (900 4150);
PAINT GREEN (900 4150);
DISPLAY INVISIBLE (900 4150);
FORCEADD TAP..6
R 2
(700 4500);
FORCEPROP 3 LASTPIN (650 4500) SIG_NAME M_K_DQS_DP<10>
J 0
(660 4510);
DISPLAY 0.659574 (660 4510);
PAINT MONO (660 4510);
DISPLAY INVISIBLE (660 4510);
FORCEPROP 1 LASTPIN (650 4500) BN 10
J 2
(700 4510);
DISPLAY 0.617021 (700 4510);
PAINT PINK (700 4510);
FORCEPROP 2 LAST CDS_LIB mstr_standard
J 0
(700 4500);
DISPLAY 0.787234 (700 4500);
PAINT MONO (700 4500);
DISPLAY INVISIBLE (700 4500);
FORCEPROP 1 LAST BODY_TYPE PLUMBING
J 2
(700 4450);
DISPLAY 1.234043 (700 4450);
PAINT GREEN (700 4450);
DISPLAY INVISIBLE (700 4450);
FORCEPROP 1 LAST HDL_TAP TRUE
J 2
(375 4375);
DISPLAY 1.234043 (375 4375);
PAINT GREEN (375 4375);
DISPLAY INVISIBLE (375 4375);
FORCEPROP 1 LAST PATH I24
J 2
(700 4500);
DISPLAY 0.936170 (700 4500);
PAINT GREEN (700 4500);
DISPLAY INVISIBLE (700 4500);
FORCEADD TAP..6
R 2
(700 4400);
FORCEPROP 3 LASTPIN (650 4400) SIG_NAME M_K_DQS_DP<9>
J 0
(660 4410);
DISPLAY 0.659574 (660 4410);
PAINT MONO (660 4410);
DISPLAY INVISIBLE (660 4410);
FORCEPROP 1 LASTPIN (650 4400) BN 9
J 2
(700 4410);
DISPLAY 0.617021 (700 4410);
PAINT PINK (700 4410);
FORCEPROP 2 LAST CDS_LIB mstr_standard
J 0
(700 4400);
DISPLAY 0.787234 (700 4400);
PAINT MONO (700 4400);
DISPLAY INVISIBLE (700 4400);
FORCEPROP 1 LAST BODY_TYPE PLUMBING
J 2
(700 4350);
DISPLAY 1.234043 (700 4350);
PAINT GREEN (700 4350);
DISPLAY INVISIBLE (700 4350);
FORCEPROP 1 LAST HDL_TAP TRUE
J 2
(375 4275);
DISPLAY 1.234043 (375 4275);
PAINT GREEN (375 4275);
DISPLAY INVISIBLE (375 4275);
FORCEPROP 1 LAST PATH I25
J 2
(700 4400);
DISPLAY 0.936170 (700 4400);
PAINT GREEN (700 4400);
DISPLAY INVISIBLE (700 4400);
FORCEADD TAP..6
R 2
(700 4100);
FORCEPROP 3 LASTPIN (650 4100) SIG_NAME M_K_DQS_DP<6>
J 0
(660 4110);
DISPLAY 0.659574 (660 4110);
PAINT MONO (660 4110);
DISPLAY INVISIBLE (660 4110);
FORCEPROP 1 LASTPIN (650 4100) BN 6
J 2
(700 4110);
DISPLAY 0.617021 (700 4110);
PAINT PINK (700 4110);
FORCEPROP 2 LAST CDS_LIB mstr_standard
J 0
(700 4100);
DISPLAY 0.787234 (700 4100);
PAINT MONO (700 4100);
DISPLAY INVISIBLE (700 4100);
FORCEPROP 1 LAST BODY_TYPE PLUMBING
J 2
(700 4050);
DISPLAY 1.234043 (700 4050);
PAINT GREEN (700 4050);
DISPLAY INVISIBLE (700 4050);
FORCEPROP 1 LAST HDL_TAP TRUE
J 2
(375 3975);
DISPLAY 1.234043 (375 3975);
PAINT GREEN (375 3975);
DISPLAY INVISIBLE (375 3975);
FORCEPROP 1 LAST PATH I26
J 2
(700 4100);
DISPLAY 0.936170 (700 4100);
PAINT GREEN (700 4100);
DISPLAY INVISIBLE (700 4100);
FORCEADD TAP..6
R 2
(700 4200);
FORCEPROP 3 LASTPIN (650 4200) SIG_NAME M_K_DQS_DP<7>
J 0
(660 4210);
DISPLAY 0.659574 (660 4210);
PAINT MONO (660 4210);
DISPLAY INVISIBLE (660 4210);
FORCEPROP 1 LASTPIN (650 4200) BN 7
J 2
(700 4210);
DISPLAY 0.617021 (700 4210);
PAINT PINK (700 4210);
FORCEPROP 2 LAST CDS_LIB mstr_standard
J 0
(700 4200);
DISPLAY 0.787234 (700 4200);
PAINT MONO (700 4200);
DISPLAY INVISIBLE (700 4200);
FORCEPROP 1 LAST BODY_TYPE PLUMBING
J 2
(700 4150);
DISPLAY 1.234043 (700 4150);
PAINT GREEN (700 4150);
DISPLAY INVISIBLE (700 4150);
FORCEPROP 1 LAST HDL_TAP TRUE
J 2
(375 4075);
DISPLAY 1.234043 (375 4075);
PAINT GREEN (375 4075);
DISPLAY INVISIBLE (375 4075);
FORCEPROP 1 LAST PATH I27
J 2
(700 4200);
DISPLAY 0.936170 (700 4200);
PAINT GREEN (700 4200);
DISPLAY INVISIBLE (700 4200);
FORCEADD TAP..6
R 2
(700 4300);
FORCEPROP 3 LASTPIN (650 4300) SIG_NAME M_K_DQS_DP<8>
J 0
(660 4310);
DISPLAY 0.659574 (660 4310);
PAINT MONO (660 4310);
DISPLAY INVISIBLE (660 4310);
FORCEPROP 1 LASTPIN (650 4300) BN 8
J 2
(700 4310);
DISPLAY 0.617021 (700 4310);
PAINT PINK (700 4310);
FORCEPROP 2 LAST CDS_LIB mstr_standard
J 0
(700 4300);
DISPLAY 0.787234 (700 4300);
PAINT MONO (700 4300);
DISPLAY INVISIBLE (700 4300);
FORCEPROP 1 LAST BODY_TYPE PLUMBING
J 2
(700 4250);
DISPLAY 1.234043 (700 4250);
PAINT GREEN (700 4250);
DISPLAY INVISIBLE (700 4250);
FORCEPROP 1 LAST HDL_TAP TRUE
J 2
(375 4175);
DISPLAY 1.234043 (375 4175);
PAINT GREEN (375 4175);
DISPLAY INVISIBLE (375 4175);
FORCEPROP 1 LAST PATH I28
J 2
(700 4300);
DISPLAY 0.936170 (700 4300);
PAINT GREEN (700 4300);
DISPLAY INVISIBLE (700 4300);
FORCEADD TAP..6
R 2
(900 4050);
FORCEPROP 3 LASTPIN (850 4050) SIG_NAME M_K_DQS_DN<6>
J 0
(860 4060);
DISPLAY 0.659574 (860 4060);
PAINT MONO (860 4060);
DISPLAY INVISIBLE (860 4060);
FORCEPROP 1 LASTPIN (850 4050) BN 6
J 2
(900 4060);
DISPLAY 0.617021 (900 4060);
PAINT PINK (900 4060);
FORCEPROP 2 LAST CDS_LIB mstr_standard
J 0
(900 4050);
DISPLAY 0.787234 (900 4050);
PAINT MONO (900 4050);
DISPLAY INVISIBLE (900 4050);
FORCEPROP 1 LAST BODY_TYPE PLUMBING
J 2
(900 4000);
DISPLAY 1.234043 (900 4000);
PAINT GREEN (900 4000);
DISPLAY INVISIBLE (900 4000);
FORCEPROP 1 LAST HDL_TAP TRUE
J 2
(575 3925);
DISPLAY 1.234043 (575 3925);
PAINT GREEN (575 3925);
DISPLAY INVISIBLE (575 3925);
FORCEPROP 1 LAST PATH I29
J 2
(900 4050);
DISPLAY 0.936170 (900 4050);
PAINT GREEN (900 4050);
DISPLAY INVISIBLE (900 4050);
FORCEADD TAP..6
R 2
(900 5150);
FORCEPROP 3 LASTPIN (850 5150) SIG_NAME M_K_DQS_DN<17>
J 0
(860 5160);
DISPLAY 0.659574 (860 5160);
PAINT MONO (860 5160);
DISPLAY INVISIBLE (860 5160);
FORCEPROP 1 LASTPIN (850 5150) BN 17
J 2
(900 5160);
DISPLAY 0.617021 (900 5160);
PAINT PINK (900 5160);
FORCEPROP 2 LAST CDS_LIB mstr_standard
J 2
(900 5150);
DISPLAY 0.787234 (900 5150);
PAINT MONO (900 5150);
DISPLAY INVISIBLE (900 5150);
FORCEPROP 1 LAST BODY_TYPE PLUMBING
J 2
(900 5100);
DISPLAY 1.234043 (900 5100);
PAINT GREEN (900 5100);
DISPLAY INVISIBLE (900 5100);
FORCEPROP 1 LAST HDL_TAP TRUE
J 2
(575 5025);
DISPLAY 1.234043 (575 5025);
PAINT GREEN (575 5025);
DISPLAY INVISIBLE (575 5025);
FORCEPROP 1 LAST PATH I3
J 2
(900 5150);
DISPLAY 0.936170 (900 5150);
PAINT GREEN (900 5150);
DISPLAY INVISIBLE (900 5150);
FORCEADD TAP..6
R 2
(900 3950);
FORCEPROP 3 LASTPIN (850 3950) SIG_NAME M_K_DQS_DN<5>
J 0
(860 3960);
DISPLAY 0.659574 (860 3960);
PAINT MONO (860 3960);
DISPLAY INVISIBLE (860 3960);
FORCEPROP 1 LASTPIN (850 3950) BN 5
J 2
(900 3960);
DISPLAY 0.617021 (900 3960);
PAINT PINK (900 3960);
FORCEPROP 2 LAST CDS_LIB mstr_standard
J 0
(900 3950);
DISPLAY 0.787234 (900 3950);
PAINT MONO (900 3950);
DISPLAY INVISIBLE (900 3950);
FORCEPROP 1 LAST BODY_TYPE PLUMBING
J 2
(900 3900);
DISPLAY 1.234043 (900 3900);
PAINT GREEN (900 3900);
DISPLAY INVISIBLE (900 3900);
FORCEPROP 1 LAST HDL_TAP TRUE
J 2
(575 3825);
DISPLAY 1.234043 (575 3825);
PAINT GREEN (575 3825);
DISPLAY INVISIBLE (575 3825);
FORCEPROP 1 LAST PATH I30
J 2
(900 3950);
DISPLAY 0.936170 (900 3950);
PAINT GREEN (900 3950);
DISPLAY INVISIBLE (900 3950);
FORCEADD TAP..6
R 2
(900 3850);
FORCEPROP 3 LASTPIN (850 3850) SIG_NAME M_K_DQS_DN<4>
J 0
(860 3860);
DISPLAY 0.659574 (860 3860);
PAINT MONO (860 3860);
DISPLAY INVISIBLE (860 3860);
FORCEPROP 1 LASTPIN (850 3850) BN 4
J 2
(900 3860);
DISPLAY 0.617021 (900 3860);
PAINT PINK (900 3860);
FORCEPROP 2 LAST CDS_LIB mstr_standard
J 0
(900 3850);
DISPLAY 0.787234 (900 3850);
PAINT MONO (900 3850);
DISPLAY INVISIBLE (900 3850);
FORCEPROP 1 LAST BODY_TYPE PLUMBING
J 2
(900 3800);
DISPLAY 1.234043 (900 3800);
PAINT GREEN (900 3800);
DISPLAY INVISIBLE (900 3800);
FORCEPROP 1 LAST HDL_TAP TRUE
J 2
(575 3725);
DISPLAY 1.234043 (575 3725);
PAINT GREEN (575 3725);
DISPLAY INVISIBLE (575 3725);
FORCEPROP 1 LAST PATH I31
J 2
(900 3850);
DISPLAY 0.936170 (900 3850);
PAINT GREEN (900 3850);
DISPLAY INVISIBLE (900 3850);
FORCEADD TAP..6
R 2
(900 3750);
FORCEPROP 3 LASTPIN (850 3750) SIG_NAME M_K_DQS_DN<3>
J 0
(860 3760);
DISPLAY 0.659574 (860 3760);
PAINT MONO (860 3760);
DISPLAY INVISIBLE (860 3760);
FORCEPROP 1 LASTPIN (850 3750) BN 3
J 2
(900 3760);
DISPLAY 0.617021 (900 3760);
PAINT PINK (900 3760);
FORCEPROP 2 LAST CDS_LIB mstr_standard
J 0
(900 3750);
DISPLAY 0.787234 (900 3750);
PAINT MONO (900 3750);
DISPLAY INVISIBLE (900 3750);
FORCEPROP 1 LAST BODY_TYPE PLUMBING
J 2
(900 3700);
DISPLAY 1.234043 (900 3700);
PAINT GREEN (900 3700);
DISPLAY INVISIBLE (900 3700);
FORCEPROP 1 LAST HDL_TAP TRUE
J 2
(575 3625);
DISPLAY 1.234043 (575 3625);
PAINT GREEN (575 3625);
DISPLAY INVISIBLE (575 3625);
FORCEPROP 1 LAST PATH I32
J 2
(900 3750);
DISPLAY 0.936170 (900 3750);
PAINT GREEN (900 3750);
DISPLAY INVISIBLE (900 3750);
FORCEADD TAP..6
R 2
(900 3650);
FORCEPROP 3 LASTPIN (850 3650) SIG_NAME M_K_DQS_DN<2>
J 0
(860 3660);
DISPLAY 0.659574 (860 3660);
PAINT MONO (860 3660);
DISPLAY INVISIBLE (860 3660);
FORCEPROP 1 LASTPIN (850 3650) BN 2
J 2
(900 3660);
DISPLAY 0.617021 (900 3660);
PAINT PINK (900 3660);
FORCEPROP 2 LAST CDS_LIB mstr_standard
J 0
(900 3650);
DISPLAY 0.787234 (900 3650);
PAINT MONO (900 3650);
DISPLAY INVISIBLE (900 3650);
FORCEPROP 1 LAST BODY_TYPE PLUMBING
J 2
(900 3600);
DISPLAY 1.234043 (900 3600);
PAINT GREEN (900 3600);
DISPLAY INVISIBLE (900 3600);
FORCEPROP 1 LAST HDL_TAP TRUE
J 2
(575 3525);
DISPLAY 1.234043 (575 3525);
PAINT GREEN (575 3525);
DISPLAY INVISIBLE (575 3525);
FORCEPROP 1 LAST PATH I33
J 2
(900 3650);
DISPLAY 0.936170 (900 3650);
PAINT GREEN (900 3650);
DISPLAY INVISIBLE (900 3650);
FORCEADD TAP..6
R 2
(700 4000);
FORCEPROP 3 LASTPIN (650 4000) SIG_NAME M_K_DQS_DP<5>
J 0
(660 4010);
DISPLAY 0.659574 (660 4010);
PAINT MONO (660 4010);
DISPLAY INVISIBLE (660 4010);
FORCEPROP 1 LASTPIN (650 4000) BN 5
J 2
(700 4010);
DISPLAY 0.617021 (700 4010);
PAINT PINK (700 4010);
FORCEPROP 2 LAST CDS_LIB mstr_standard
J 0
(700 4000);
DISPLAY 0.787234 (700 4000);
PAINT MONO (700 4000);
DISPLAY INVISIBLE (700 4000);
FORCEPROP 1 LAST BODY_TYPE PLUMBING
J 2
(700 3950);
DISPLAY 1.234043 (700 3950);
PAINT GREEN (700 3950);
DISPLAY INVISIBLE (700 3950);
FORCEPROP 1 LAST HDL_TAP TRUE
J 2
(375 3875);
DISPLAY 1.234043 (375 3875);
PAINT GREEN (375 3875);
DISPLAY INVISIBLE (375 3875);
FORCEPROP 1 LAST PATH I34
J 2
(700 4000);
DISPLAY 0.936170 (700 4000);
PAINT GREEN (700 4000);
DISPLAY INVISIBLE (700 4000);
FORCEADD TAP..6
R 2
(700 3900);
FORCEPROP 3 LASTPIN (650 3900) SIG_NAME M_K_DQS_DP<4>
J 0
(660 3910);
DISPLAY 0.659574 (660 3910);
PAINT MONO (660 3910);
DISPLAY INVISIBLE (660 3910);
FORCEPROP 1 LASTPIN (650 3900) BN 4
J 2
(700 3910);
DISPLAY 0.617021 (700 3910);
PAINT PINK (700 3910);
FORCEPROP 2 LAST CDS_LIB mstr_standard
J 0
(700 3900);
DISPLAY 0.787234 (700 3900);
PAINT MONO (700 3900);
DISPLAY INVISIBLE (700 3900);
FORCEPROP 1 LAST BODY_TYPE PLUMBING
J 2
(700 3850);
DISPLAY 1.234043 (700 3850);
PAINT GREEN (700 3850);
DISPLAY INVISIBLE (700 3850);
FORCEPROP 1 LAST HDL_TAP TRUE
J 2
(375 3775);
DISPLAY 1.234043 (375 3775);
PAINT GREEN (375 3775);
DISPLAY INVISIBLE (375 3775);
FORCEPROP 1 LAST PATH I35
J 2
(700 3900);
DISPLAY 0.936170 (700 3900);
PAINT GREEN (700 3900);
DISPLAY INVISIBLE (700 3900);
FORCEADD TAP..6
R 2
(700 3700);
FORCEPROP 3 LASTPIN (650 3700) SIG_NAME M_K_DQS_DP<2>
J 0
(660 3710);
DISPLAY 0.659574 (660 3710);
PAINT MONO (660 3710);
DISPLAY INVISIBLE (660 3710);
FORCEPROP 1 LASTPIN (650 3700) BN 2
J 2
(700 3710);
DISPLAY 0.617021 (700 3710);
PAINT PINK (700 3710);
FORCEPROP 2 LAST CDS_LIB mstr_standard
J 0
(700 3700);
DISPLAY 0.787234 (700 3700);
PAINT MONO (700 3700);
DISPLAY INVISIBLE (700 3700);
FORCEPROP 1 LAST BODY_TYPE PLUMBING
J 2
(700 3650);
DISPLAY 1.234043 (700 3650);
PAINT GREEN (700 3650);
DISPLAY INVISIBLE (700 3650);
FORCEPROP 1 LAST HDL_TAP TRUE
J 2
(375 3575);
DISPLAY 1.234043 (375 3575);
PAINT GREEN (375 3575);
DISPLAY INVISIBLE (375 3575);
FORCEPROP 1 LAST PATH I36
J 2
(700 3700);
DISPLAY 0.936170 (700 3700);
PAINT GREEN (700 3700);
DISPLAY INVISIBLE (700 3700);
FORCEADD TAP..6
R 2
(700 3600);
FORCEPROP 3 LASTPIN (650 3600) SIG_NAME M_K_DQS_DP<1>
J 0
(660 3610);
DISPLAY 0.659574 (660 3610);
PAINT MONO (660 3610);
DISPLAY INVISIBLE (660 3610);
FORCEPROP 1 LASTPIN (650 3600) BN 1
J 2
(700 3610);
DISPLAY 0.617021 (700 3610);
PAINT PINK (700 3610);
FORCEPROP 2 LAST CDS_LIB mstr_standard
J 0
(700 3600);
DISPLAY 0.787234 (700 3600);
PAINT MONO (700 3600);
DISPLAY INVISIBLE (700 3600);
FORCEPROP 1 LAST BODY_TYPE PLUMBING
J 2
(700 3550);
DISPLAY 1.234043 (700 3550);
PAINT GREEN (700 3550);
DISPLAY INVISIBLE (700 3550);
FORCEPROP 1 LAST HDL_TAP TRUE
J 2
(375 3475);
DISPLAY 1.234043 (375 3475);
PAINT GREEN (375 3475);
DISPLAY INVISIBLE (375 3475);
FORCEPROP 1 LAST PATH I37
J 2
(700 3600);
DISPLAY 0.936170 (700 3600);
PAINT GREEN (700 3600);
DISPLAY INVISIBLE (700 3600);
FORCEADD TAP..6
R 2
(700 3800);
FORCEPROP 3 LASTPIN (650 3800) SIG_NAME M_K_DQS_DP<3>
J 0
(660 3810);
DISPLAY 0.659574 (660 3810);
PAINT MONO (660 3810);
DISPLAY INVISIBLE (660 3810);
FORCEPROP 1 LASTPIN (650 3800) BN 3
J 2
(700 3810);
DISPLAY 0.617021 (700 3810);
PAINT PINK (700 3810);
FORCEPROP 2 LAST CDS_LIB mstr_standard
J 0
(700 3800);
DISPLAY 0.787234 (700 3800);
PAINT MONO (700 3800);
DISPLAY INVISIBLE (700 3800);
FORCEPROP 1 LAST BODY_TYPE PLUMBING
J 2
(700 3750);
DISPLAY 1.234043 (700 3750);
PAINT GREEN (700 3750);
DISPLAY INVISIBLE (700 3750);
FORCEPROP 1 LAST HDL_TAP TRUE
J 2
(375 3675);
DISPLAY 1.234043 (375 3675);
PAINT GREEN (375 3675);
DISPLAY INVISIBLE (375 3675);
FORCEPROP 1 LAST PATH I38
J 2
(700 3800);
DISPLAY 0.936170 (700 3800);
PAINT GREEN (700 3800);
DISPLAY INVISIBLE (700 3800);
FORCEADD TAP..6
R 2
(900 3450);
FORCEPROP 3 LASTPIN (850 3450) SIG_NAME M_K_DQS_DN<0>
J 0
(860 3460);
DISPLAY 0.659574 (860 3460);
PAINT MONO (860 3460);
DISPLAY INVISIBLE (860 3460);
FORCEPROP 1 LASTPIN (850 3450) BN 0
J 2
(900 3460);
DISPLAY 0.617021 (900 3460);
PAINT PINK (900 3460);
FORCEPROP 2 LAST CDS_LIB mstr_standard
J 0
(900 3450);
DISPLAY 0.787234 (900 3450);
PAINT MONO (900 3450);
DISPLAY INVISIBLE (900 3450);
FORCEPROP 1 LAST BODY_TYPE PLUMBING
J 2
(900 3400);
DISPLAY 1.234043 (900 3400);
PAINT GREEN (900 3400);
DISPLAY INVISIBLE (900 3400);
FORCEPROP 1 LAST HDL_TAP TRUE
J 2
(575 3325);
DISPLAY 1.234043 (575 3325);
PAINT GREEN (575 3325);
DISPLAY INVISIBLE (575 3325);
FORCEPROP 1 LAST PATH I39
J 2
(900 3450);
DISPLAY 0.936170 (900 3450);
PAINT GREEN (900 3450);
DISPLAY INVISIBLE (900 3450);
FORCEADD TAP..6
R 2
(700 5200);
FORCEPROP 3 LASTPIN (650 5200) SIG_NAME M_K_DQS_DP<17>
J 0
(660 5210);
DISPLAY 0.659574 (660 5210);
PAINT MONO (660 5210);
DISPLAY INVISIBLE (660 5210);
FORCEPROP 1 LASTPIN (650 5200) BN 17
J 2
(700 5210);
DISPLAY 0.617021 (700 5210);
PAINT PINK (700 5210);
FORCEPROP 2 LAST CDS_LIB mstr_standard
J 2
(700 5200);
DISPLAY 0.787234 (700 5200);
PAINT MONO (700 5200);
DISPLAY INVISIBLE (700 5200);
FORCEPROP 1 LAST BODY_TYPE PLUMBING
J 2
(700 5150);
DISPLAY 1.234043 (700 5150);
PAINT GREEN (700 5150);
DISPLAY INVISIBLE (700 5150);
FORCEPROP 1 LAST HDL_TAP TRUE
J 2
(375 5075);
DISPLAY 1.234043 (375 5075);
PAINT GREEN (375 5075);
DISPLAY INVISIBLE (375 5075);
FORCEPROP 1 LAST PATH I4
J 2
(700 5200);
DISPLAY 0.936170 (700 5200);
PAINT GREEN (700 5200);
DISPLAY INVISIBLE (700 5200);
FORCEADD TAP..6
R 2
(900 3550);
FORCEPROP 3 LASTPIN (850 3550) SIG_NAME M_K_DQS_DN<1>
J 0
(860 3560);
DISPLAY 0.659574 (860 3560);
PAINT MONO (860 3560);
DISPLAY INVISIBLE (860 3560);
FORCEPROP 1 LASTPIN (850 3550) BN 1
J 2
(900 3560);
DISPLAY 0.617021 (900 3560);
PAINT PINK (900 3560);
FORCEPROP 2 LAST CDS_LIB mstr_standard
J 0
(900 3550);
DISPLAY 0.787234 (900 3550);
PAINT MONO (900 3550);
DISPLAY INVISIBLE (900 3550);
FORCEPROP 1 LAST BODY_TYPE PLUMBING
J 2
(900 3500);
DISPLAY 1.234043 (900 3500);
PAINT GREEN (900 3500);
DISPLAY INVISIBLE (900 3500);
FORCEPROP 1 LAST HDL_TAP TRUE
J 2
(575 3425);
DISPLAY 1.234043 (575 3425);
PAINT GREEN (575 3425);
DISPLAY INVISIBLE (575 3425);
FORCEPROP 1 LAST PATH I40
J 2
(900 3550);
DISPLAY 0.936170 (900 3550);
PAINT GREEN (900 3550);
DISPLAY INVISIBLE (900 3550);
FORCEADD TAP..6
R 2
(700 3500);
FORCEPROP 3 LASTPIN (650 3500) SIG_NAME M_K_DQS_DP<0>
J 0
(660 3510);
DISPLAY 0.659574 (660 3510);
PAINT MONO (660 3510);
DISPLAY INVISIBLE (660 3510);
FORCEPROP 1 LASTPIN (650 3500) BN 0
J 2
(700 3510);
DISPLAY 0.617021 (700 3510);
PAINT PINK (700 3510);
FORCEPROP 2 LAST CDS_LIB mstr_standard
J 0
(700 3500);
DISPLAY 0.787234 (700 3500);
PAINT MONO (700 3500);
DISPLAY INVISIBLE (700 3500);
FORCEPROP 1 LAST BODY_TYPE PLUMBING
J 2
(700 3450);
DISPLAY 1.234043 (700 3450);
PAINT GREEN (700 3450);
DISPLAY INVISIBLE (700 3450);
FORCEPROP 1 LAST HDL_TAP TRUE
J 2
(375 3375);
DISPLAY 1.234043 (375 3375);
PAINT GREEN (375 3375);
DISPLAY INVISIBLE (375 3375);
FORCEPROP 1 LAST PATH I41
J 2
(700 3500);
DISPLAY 0.936170 (700 3500);
PAINT GREEN (700 3500);
DISPLAY INVISIBLE (700 3500);
FORCEADD SCONN288_H44441004..3
(1800 2400);
FORCEPROP 1 LAST LOCATION J1B1
J 0
(1350 3800);
DISPLAY 0.617021 (1350 3800);
PAINT AQUA (1350 3800);
FORCEPROP 1 LAST PART_NUMBER H44441-004
J 0
(1350 1050);
DISPLAY 0.617021 (1350 1050);
PAINT BLUE (1350 1050);
FORCEPROP 1 LAST MATERIAL SCONN
J 0
(1350 3750);
DISPLAY 0.617021 (1350 3750);
PAINT SKYBLUE (1350 3750);
FORCEPROP 2 LASTPIN (1300 3550) $PN 2
J 2
(1290 3560);
DISPLAY 0.617021 (1290 3560);
PAINT ORANGE (1290 3560);
FORCEPROP 2 LASTPIN (1300 3500) $PN 4
J 2
(1290 3510);
DISPLAY 0.617021 (1290 3510);
PAINT ORANGE (1290 3510);
FORCEPROP 2 LASTPIN (1300 3450) $PN 6
J 2
(1290 3460);
DISPLAY 0.617021 (1290 3460);
PAINT ORANGE (1290 3460);
FORCEPROP 2 LASTPIN (1300 3400) $PN 9
J 2
(1290 3410);
DISPLAY 0.617021 (1290 3410);
PAINT ORANGE (1290 3410);
FORCEPROP 2 LASTPIN (1300 3350) $PN 11
J 2
(1290 3360);
DISPLAY 0.617021 (1290 3360);
PAINT ORANGE (1290 3360);
FORCEPROP 2 LASTPIN (1300 3300) $PN 13
J 2
(1290 3310);
DISPLAY 0.617021 (1290 3310);
PAINT ORANGE (1290 3310);
FORCEPROP 2 LASTPIN (1300 3250) $PN 15
J 2
(1290 3260);
DISPLAY 0.617021 (1290 3260);
PAINT ORANGE (1290 3260);
FORCEPROP 2 LASTPIN (1300 3200) $PN 17
J 2
(1290 3210);
DISPLAY 0.617021 (1290 3210);
PAINT ORANGE (1290 3210);
FORCEPROP 2 LASTPIN (1300 3150) $PN 20
J 2
(1290 3160);
DISPLAY 0.617021 (1290 3160);
PAINT ORANGE (1290 3160);
FORCEPROP 2 LASTPIN (1300 3100) $PN 22
J 2
(1290 3110);
DISPLAY 0.617021 (1290 3110);
PAINT ORANGE (1290 3110);
FORCEPROP 2 LASTPIN (1300 3050) $PN 24
J 2
(1290 3060);
DISPLAY 0.617021 (1290 3060);
PAINT ORANGE (1290 3060);
FORCEPROP 2 LASTPIN (1300 3000) $PN 26
J 2
(1290 3010);
DISPLAY 0.617021 (1290 3010);
PAINT ORANGE (1290 3010);
FORCEPROP 2 LASTPIN (1300 2950) $PN 28
J 2
(1290 2960);
DISPLAY 0.617021 (1290 2960);
PAINT ORANGE (1290 2960);
FORCEPROP 2 LASTPIN (1300 2900) $PN 31
J 2
(1290 2910);
DISPLAY 0.617021 (1290 2910);
PAINT ORANGE (1290 2910);
FORCEPROP 2 LASTPIN (1300 2850) $PN 33
J 2
(1290 2860);
DISPLAY 0.617021 (1290 2860);
PAINT ORANGE (1290 2860);
FORCEPROP 2 LASTPIN (1300 2800) $PN 35
J 2
(1290 2810);
DISPLAY 0.617021 (1290 2810);
PAINT ORANGE (1290 2810);
FORCEPROP 2 LASTPIN (1300 2750) $PN 37
J 2
(1290 2760);
DISPLAY 0.617021 (1290 2760);
PAINT ORANGE (1290 2760);
FORCEPROP 2 LASTPIN (1300 2700) $PN 39
J 2
(1290 2710);
DISPLAY 0.617021 (1290 2710);
PAINT ORANGE (1290 2710);
FORCEPROP 2 LASTPIN (1300 2650) $PN 42
J 2
(1290 2660);
DISPLAY 0.617021 (1290 2660);
PAINT ORANGE (1290 2660);
FORCEPROP 2 LASTPIN (1300 2600) $PN 44
J 2
(1290 2610);
DISPLAY 0.617021 (1290 2610);
PAINT ORANGE (1290 2610);
FORCEPROP 2 LASTPIN (1300 2550) $PN 46
J 2
(1290 2560);
DISPLAY 0.617021 (1290 2560);
PAINT ORANGE (1290 2560);
FORCEPROP 2 LASTPIN (1300 2500) $PN 48
J 2
(1290 2510);
DISPLAY 0.617021 (1290 2510);
PAINT ORANGE (1290 2510);
FORCEPROP 2 LASTPIN (1300 2450) $PN 50
J 2
(1290 2460);
DISPLAY 0.617021 (1290 2460);
PAINT ORANGE (1290 2460);
FORCEPROP 2 LASTPIN (1300 2400) $PN 53
J 2
(1290 2410);
DISPLAY 0.617021 (1290 2410);
PAINT ORANGE (1290 2410);
FORCEPROP 2 LASTPIN (1300 2350) $PN 55
J 2
(1290 2360);
DISPLAY 0.617021 (1290 2360);
PAINT ORANGE (1290 2360);
FORCEPROP 2 LASTPIN (1300 2300) $PN 57
J 2
(1290 2310);
DISPLAY 0.617021 (1290 2310);
PAINT ORANGE (1290 2310);
FORCEPROP 2 LASTPIN (1300 2250) $PN 94
J 2
(1290 2260);
DISPLAY 0.617021 (1290 2260);
PAINT ORANGE (1290 2260);
FORCEPROP 2 LASTPIN (1300 2200) $PN 96
J 2
(1290 2210);
DISPLAY 0.617021 (1290 2210);
PAINT ORANGE (1290 2210);
FORCEPROP 2 LASTPIN (1300 2150) $PN 98
J 2
(1290 2160);
DISPLAY 0.617021 (1290 2160);
PAINT ORANGE (1290 2160);
FORCEPROP 2 LASTPIN (1300 2100) $PN 101
J 2
(1290 2110);
DISPLAY 0.617021 (1290 2110);
PAINT ORANGE (1290 2110);
FORCEPROP 2 LASTPIN (1300 2050) $PN 103
J 2
(1290 2060);
DISPLAY 0.617021 (1290 2060);
PAINT ORANGE (1290 2060);
FORCEPROP 2 LASTPIN (1300 2000) $PN 105
J 2
(1290 2010);
DISPLAY 0.617021 (1290 2010);
PAINT ORANGE (1290 2010);
FORCEPROP 2 LASTPIN (1300 1950) $PN 107
J 2
(1290 1960);
DISPLAY 0.617021 (1290 1960);
PAINT ORANGE (1290 1960);
FORCEPROP 2 LASTPIN (1300 1900) $PN 109
J 2
(1290 1910);
DISPLAY 0.617021 (1290 1910);
PAINT ORANGE (1290 1910);
FORCEPROP 2 LASTPIN (1300 1850) $PN 112
J 2
(1290 1860);
DISPLAY 0.617021 (1290 1860);
PAINT ORANGE (1290 1860);
FORCEPROP 2 LASTPIN (1300 1800) $PN 114
J 2
(1290 1810);
DISPLAY 0.617021 (1290 1810);
PAINT ORANGE (1290 1810);
FORCEPROP 2 LASTPIN (1300 1750) $PN 116
J 2
(1290 1760);
DISPLAY 0.617021 (1290 1760);
PAINT ORANGE (1290 1760);
FORCEPROP 2 LASTPIN (1300 1700) $PN 118
J 2
(1290 1710);
DISPLAY 0.617021 (1290 1710);
PAINT ORANGE (1290 1710);
FORCEPROP 2 LASTPIN (1300 1650) $PN 120
J 2
(1290 1660);
DISPLAY 0.617021 (1290 1660);
PAINT ORANGE (1290 1660);
FORCEPROP 2 LASTPIN (1300 1600) $PN 123
J 2
(1290 1610);
DISPLAY 0.617021 (1290 1610);
PAINT ORANGE (1290 1610);
FORCEPROP 2 LASTPIN (1300 1550) $PN 125
J 2
(1290 1560);
DISPLAY 0.617021 (1290 1560);
PAINT ORANGE (1290 1560);
FORCEPROP 2 LASTPIN (1300 1500) $PN 127
J 2
(1290 1510);
DISPLAY 0.617021 (1290 1510);
PAINT ORANGE (1290 1510);
FORCEPROP 2 LASTPIN (1300 1450) $PN 129
J 2
(1290 1460);
DISPLAY 0.617021 (1290 1460);
PAINT ORANGE (1290 1460);
FORCEPROP 2 LASTPIN (1300 1400) $PN 131
J 2
(1290 1410);
DISPLAY 0.617021 (1290 1410);
PAINT ORANGE (1290 1410);
FORCEPROP 2 LASTPIN (1300 1350) $PN 134
J 2
(1290 1360);
DISPLAY 0.617021 (1290 1360);
PAINT ORANGE (1290 1360);
FORCEPROP 2 LASTPIN (1300 1300) $PN 136
J 2
(1290 1310);
DISPLAY 0.617021 (1290 1310);
PAINT ORANGE (1290 1310);
FORCEPROP 2 LASTPIN (1300 1250) $PN 138
J 2
(1290 1260);
DISPLAY 0.617021 (1290 1260);
PAINT ORANGE (1290 1260);
FORCEPROP 2 LASTPIN (2300 3550) $PN 147
J 0
(2310 3560);
DISPLAY 0.617021 (2310 3560);
PAINT ORANGE (2310 3560);
FORCEPROP 2 LASTPIN (2300 3500) $PN 149
J 0
(2310 3510);
DISPLAY 0.617021 (2310 3510);
PAINT ORANGE (2310 3510);
FORCEPROP 2 LASTPIN (2300 3450) $PN 151
J 0
(2310 3460);
DISPLAY 0.617021 (2310 3460);
PAINT ORANGE (2310 3460);
FORCEPROP 2 LASTPIN (2300 3400) $PN 154
J 0
(2310 3410);
DISPLAY 0.617021 (2310 3410);
PAINT ORANGE (2310 3410);
FORCEPROP 2 LASTPIN (2300 3350) $PN 156
J 0
(2310 3360);
DISPLAY 0.617021 (2310 3360);
PAINT ORANGE (2310 3360);
FORCEPROP 2 LASTPIN (2300 3300) $PN 158
J 0
(2310 3310);
DISPLAY 0.617021 (2310 3310);
PAINT ORANGE (2310 3310);
FORCEPROP 2 LASTPIN (2300 3250) $PN 160
J 0
(2310 3260);
DISPLAY 0.617021 (2310 3260);
PAINT ORANGE (2310 3260);
FORCEPROP 2 LASTPIN (2300 3200) $PN 162
J 0
(2310 3210);
DISPLAY 0.617021 (2310 3210);
PAINT ORANGE (2310 3210);
FORCEPROP 2 LASTPIN (2300 3150) $PN 165
J 0
(2310 3160);
DISPLAY 0.617021 (2310 3160);
PAINT ORANGE (2310 3160);
FORCEPROP 2 LASTPIN (2300 3100) $PN 167
J 0
(2310 3110);
DISPLAY 0.617021 (2310 3110);
PAINT ORANGE (2310 3110);
FORCEPROP 2 LASTPIN (2300 3050) $PN 169
J 0
(2310 3060);
DISPLAY 0.617021 (2310 3060);
PAINT ORANGE (2310 3060);
FORCEPROP 2 LASTPIN (2300 3000) $PN 171
J 0
(2310 3010);
DISPLAY 0.617021 (2310 3010);
PAINT ORANGE (2310 3010);
FORCEPROP 2 LASTPIN (2300 2950) $PN 173
J 0
(2310 2960);
DISPLAY 0.617021 (2310 2960);
PAINT ORANGE (2310 2960);
FORCEPROP 2 LASTPIN (2300 2900) $PN 176
J 0
(2310 2910);
DISPLAY 0.617021 (2310 2910);
PAINT ORANGE (2310 2910);
FORCEPROP 2 LASTPIN (2300 2850) $PN 178
J 0
(2310 2860);
DISPLAY 0.617021 (2310 2860);
PAINT ORANGE (2310 2860);
FORCEPROP 2 LASTPIN (2300 2800) $PN 180
J 0
(2310 2810);
DISPLAY 0.617021 (2310 2810);
PAINT ORANGE (2310 2810);
FORCEPROP 2 LASTPIN (2300 2750) $PN 182
J 0
(2310 2760);
DISPLAY 0.617021 (2310 2760);
PAINT ORANGE (2310 2760);
FORCEPROP 2 LASTPIN (2300 2700) $PN 184
J 0
(2310 2710);
DISPLAY 0.617021 (2310 2710);
PAINT ORANGE (2310 2710);
FORCEPROP 2 LASTPIN (2300 2650) $PN 187
J 0
(2310 2660);
DISPLAY 0.617021 (2310 2660);
PAINT ORANGE (2310 2660);
FORCEPROP 2 LASTPIN (2300 2600) $PN 189
J 0
(2310 2610);
DISPLAY 0.617021 (2310 2610);
PAINT ORANGE (2310 2610);
FORCEPROP 2 LASTPIN (2300 2550) $PN 191
J 0
(2310 2560);
DISPLAY 0.617021 (2310 2560);
PAINT ORANGE (2310 2560);
FORCEPROP 2 LASTPIN (2300 2500) $PN 193
J 0
(2310 2510);
DISPLAY 0.617021 (2310 2510);
PAINT ORANGE (2310 2510);
FORCEPROP 2 LASTPIN (2300 2450) $PN 195
J 0
(2310 2460);
DISPLAY 0.617021 (2310 2460);
PAINT ORANGE (2310 2460);
FORCEPROP 2 LASTPIN (2300 2400) $PN 198
J 0
(2310 2410);
DISPLAY 0.617021 (2310 2410);
PAINT ORANGE (2310 2410);
FORCEPROP 2 LASTPIN (2300 2350) $PN 200
J 0
(2310 2360);
DISPLAY 0.617021 (2310 2360);
PAINT ORANGE (2310 2360);
FORCEPROP 2 LASTPIN (2300 2300) $PN 202
J 0
(2310 2310);
DISPLAY 0.617021 (2310 2310);
PAINT ORANGE (2310 2310);
FORCEPROP 2 LASTPIN (2300 2250) $PN 239
J 0
(2310 2260);
DISPLAY 0.617021 (2310 2260);
PAINT ORANGE (2310 2260);
FORCEPROP 2 LASTPIN (2300 2200) $PN 241
J 0
(2310 2210);
DISPLAY 0.617021 (2310 2210);
PAINT ORANGE (2310 2210);
FORCEPROP 2 LASTPIN (2300 2150) $PN 243
J 0
(2310 2160);
DISPLAY 0.617021 (2310 2160);
PAINT ORANGE (2310 2160);
FORCEPROP 2 LASTPIN (2300 2100) $PN 246
J 0
(2310 2110);
DISPLAY 0.617021 (2310 2110);
PAINT ORANGE (2310 2110);
FORCEPROP 2 LASTPIN (2300 2050) $PN 248
J 0
(2310 2060);
DISPLAY 0.617021 (2310 2060);
PAINT ORANGE (2310 2060);
FORCEPROP 2 LASTPIN (2300 2000) $PN 250
J 0
(2310 2010);
DISPLAY 0.617021 (2310 2010);
PAINT ORANGE (2310 2010);
FORCEPROP 2 LASTPIN (2300 1950) $PN 252
J 0
(2310 1960);
DISPLAY 0.617021 (2310 1960);
PAINT ORANGE (2310 1960);
FORCEPROP 2 LASTPIN (2300 1900) $PN 254
J 0
(2310 1910);
DISPLAY 0.617021 (2310 1910);
PAINT ORANGE (2310 1910);
FORCEPROP 2 LASTPIN (2300 1850) $PN 257
J 0
(2310 1860);
DISPLAY 0.617021 (2310 1860);
PAINT ORANGE (2310 1860);
FORCEPROP 2 LASTPIN (2300 1800) $PN 259
J 0
(2310 1810);
DISPLAY 0.617021 (2310 1810);
PAINT ORANGE (2310 1810);
FORCEPROP 2 LASTPIN (2300 1750) $PN 261
J 0
(2310 1760);
DISPLAY 0.617021 (2310 1760);
PAINT ORANGE (2310 1760);
FORCEPROP 2 LASTPIN (2300 1700) $PN 263
J 0
(2310 1710);
DISPLAY 0.617021 (2310 1710);
PAINT ORANGE (2310 1710);
FORCEPROP 2 LASTPIN (2300 1650) $PN 265
J 0
(2310 1660);
DISPLAY 0.617021 (2310 1660);
PAINT ORANGE (2310 1660);
FORCEPROP 2 LASTPIN (2300 1600) $PN 268
J 0
(2310 1610);
DISPLAY 0.617021 (2310 1610);
PAINT ORANGE (2310 1610);
FORCEPROP 2 LASTPIN (2300 1550) $PN 270
J 0
(2310 1560);
DISPLAY 0.617021 (2310 1560);
PAINT ORANGE (2310 1560);
FORCEPROP 2 LASTPIN (2300 1500) $PN 272
J 0
(2310 1510);
DISPLAY 0.617021 (2310 1510);
PAINT ORANGE (2310 1510);
FORCEPROP 2 LASTPIN (2300 1450) $PN 274
J 0
(2310 1460);
DISPLAY 0.617021 (2310 1460);
PAINT ORANGE (2310 1460);
FORCEPROP 2 LASTPIN (2300 1400) $PN 276
J 0
(2310 1410);
DISPLAY 0.617021 (2310 1410);
PAINT ORANGE (2310 1410);
FORCEPROP 2 LASTPIN (2300 1350) $PN 279
J 0
(2310 1360);
DISPLAY 0.617021 (2310 1360);
PAINT ORANGE (2310 1360);
FORCEPROP 2 LASTPIN (2300 1300) $PN 281
J 0
(2310 1310);
DISPLAY 0.617021 (2310 1310);
PAINT ORANGE (2310 1310);
FORCEPROP 2 LASTPIN (2300 1250) $PN 283
J 0
(2310 1260);
DISPLAY 0.617021 (2310 1260);
PAINT ORANGE (2310 1260);
FORCEPROP 1 LAST PACK_TYPE PIP
J 0
(1350 3850);
PAINT SKYBLUE (1350 3850);
DISPLAY INVISIBLE (1350 3850);
FORCEPROP 2 LAST BOM_COST MEM
J 0
(1800 2400);
PAINT ORANGE (1800 2400);
DISPLAY INVISIBLE (1800 2400);
FORCEPROP 2 LAST CDS_LIB mstr_sconn
J 0
(1800 2400);
PAINT ORANGE (1800 2400);
DISPLAY INVISIBLE (1800 2400);
FORCEPROP 2 LAST SEC_TYPE PIP
J 0
(1350 3850);
DISPLAY 1.021277 (1350 3850);
PAINT ORANGE (1350 3850);
DISPLAY INVISIBLE (1350 3850);
FORCEPROP 2 LAST SEC 3
J 0
(1350 3850);
DISPLAY 0.680851 (1350 3850);
PAINT MONO (1350 3850);
DISPLAY INVISIBLE (1350 3850);
FORCEPROP 2 LAST CDS_LOCATION J1B1
J 0
(1350 3800);
DISPLAY 0.617021 (1350 3800);
PAINT AQUA (1350 3800);
DISPLAY INVISIBLE (1350 3800);
FORCEPROP 1 LAST PATH I43
J 0
(1800 3750);
PAINT GREEN (1800 3750);
DISPLAY INVISIBLE (1800 3750);
FORCEPROP 2 LAST ROOM DDR4_CH_K
J 0
(1800 2400);
PAINT ORANGE (1800 2400);
DISPLAY INVISIBLE (1800 2400);
FORCEADD GND..1
R 2
(1100 1100);
FORCEPROP 3 LASTPIN (1100 1150) SIG_NAME GND\g
J 0
(1110 1160);
DISPLAY 0.659574 (1110 1160);
PAINT MONO (1110 1160);
DISPLAY INVISIBLE (1110 1160);
FORCEPROP 1 LAST VOLTAGE 0
J 0
(1100 1100);
PAINT SKYBLUE (1100 1100);
DISPLAY INVISIBLE (1100 1100);
FORCEPROP 2 LAST BOM_COST MEM
J 0
(1100 1105);
PAINT ORANGE (1100 1105);
DISPLAY INVISIBLE (1100 1105);
FORCEPROP 1 LAST SIZE 1B
J 2
(1025 1050);
DISPLAY 1.170213 (1025 1050);
PAINT GREEN (1025 1050);
DISPLAY INVISIBLE (1025 1050);
FORCEPROP 2 LAST CDS_LIB mstr_symbols
J 0
(1100 1100);
DISPLAY 0.787234 (1100 1100);
PAINT MONO (1100 1100);
DISPLAY INVISIBLE (1100 1100);
FORCEPROP 1 LAST BODY_TYPE PLUMBING
J 2
(1145 1057);
DISPLAY 0.340426 (1145 1057);
PAINT GREEN (1145 1057);
DISPLAY INVISIBLE (1145 1057);
FORCEPROP 1 LAST PATH I44
J 2
(1025 1100);
DISPLAY 0.936170 (1025 1100);
PAINT GREEN (1025 1100);
DISPLAY INVISIBLE (1025 1100);
FORCEPROP 2 LAST ROOM DDR4_CH_C
J 0
(1100 1105);
PAINT ORANGE (1100 1105);
DISPLAY INVISIBLE (1100 1105);
FORCEPROP 1 LAST HDL_POWER GND
J 2
(1100 1250);
DISPLAY 0.553191 (1100 1250);
PAINT GREEN (1100 1250);
DISPLAY INVISIBLE (1100 1250);
FORCEADD OFFPAGE..3
(-1100 4900);
FORCEPROP 2 LAST $XR0 60 
J 0
(-886 4900);
DISPLAY 0.638298 (-886 4900);
PAINT MONO (-886 4900);
FORCEPROP 2 LAST $XR1 84 
J 0
(-796 4900);
DISPLAY 0.638298 (-796 4900);
PAINT MONO (-796 4900);
FORCEPROP 2 LAST CDS_LIB mstr_standard
J 0
(-1100 4900);
DISPLAY 0.787234 (-1100 4900);
PAINT MONO (-1100 4900);
DISPLAY INVISIBLE (-1100 4900);
FORCEPROP 1 LAST OFFPAGE TRUE
J 0
(-775 4775);
DISPLAY 0.936170 (-775 4775);
PAINT GREEN (-775 4775);
DISPLAY INVISIBLE (-775 4775);
FORCEPROP 1 LAST COMMENT_BODY TRUE
J 0
(-1150 4800);
DISPLAY 0.936170 (-1150 4800);
PAINT GREEN (-1150 4800);
DISPLAY INVISIBLE (-1150 4800);
FORCEPROP 2 LAST PATH I45
J 0
(-900 4975);
DISPLAY 0.787234 (-900 4975);
PAINT MONO (-900 4975);
DISPLAY INVISIBLE (-900 4975);
FORCEADD TAP..6
R 2
(-1700 4750);
FORCEPROP 3 LASTPIN (-1750 4750) SIG_NAME M_K_DQ<60>
J 0
(-1740 4760);
DISPLAY 0.659574 (-1740 4760);
PAINT MONO (-1740 4760);
DISPLAY INVISIBLE (-1740 4760);
FORCEPROP 1 LASTPIN (-1750 4750) BN 60
J 2
(-1700 4760);
DISPLAY 0.617021 (-1700 4760);
PAINT PINK (-1700 4760);
FORCEPROP 2 LAST CDS_LIB mstr_standard
J 2
(-1700 4750);
DISPLAY 0.787234 (-1700 4750);
PAINT MONO (-1700 4750);
DISPLAY INVISIBLE (-1700 4750);
FORCEPROP 1 LAST BODY_TYPE PLUMBING
J 2
(-1700 4700);
DISPLAY 1.234043 (-1700 4700);
PAINT GREEN (-1700 4700);
DISPLAY INVISIBLE (-1700 4700);
FORCEPROP 1 LAST HDL_TAP TRUE
J 2
(-2025 4625);
DISPLAY 1.234043 (-2025 4625);
PAINT GREEN (-2025 4625);
DISPLAY INVISIBLE (-2025 4625);
FORCEPROP 1 LAST PATH I46
J 2
(-1700 4750);
DISPLAY 0.936170 (-1700 4750);
PAINT GREEN (-1700 4750);
DISPLAY INVISIBLE (-1700 4750);
FORCEADD TAP..6
R 2
(-1700 4700);
FORCEPROP 3 LASTPIN (-1750 4700) SIG_NAME M_K_DQ<61>
J 0
(-1740 4710);
DISPLAY 0.659574 (-1740 4710);
PAINT MONO (-1740 4710);
DISPLAY INVISIBLE (-1740 4710);
FORCEPROP 1 LASTPIN (-1750 4700) BN 61
J 2
(-1700 4710);
DISPLAY 0.617021 (-1700 4710);
PAINT PINK (-1700 4710);
FORCEPROP 2 LAST CDS_LIB mstr_standard
J 2
(-1700 4700);
DISPLAY 0.787234 (-1700 4700);
PAINT MONO (-1700 4700);
DISPLAY INVISIBLE (-1700 4700);
FORCEPROP 1 LAST BODY_TYPE PLUMBING
J 2
(-1700 4650);
DISPLAY 1.234043 (-1700 4650);
PAINT GREEN (-1700 4650);
DISPLAY INVISIBLE (-1700 4650);
FORCEPROP 1 LAST HDL_TAP TRUE
J 2
(-2025 4575);
DISPLAY 1.234043 (-2025 4575);
PAINT GREEN (-2025 4575);
DISPLAY INVISIBLE (-2025 4575);
FORCEPROP 1 LAST PATH I47
J 2
(-1700 4700);
DISPLAY 0.936170 (-1700 4700);
PAINT GREEN (-1700 4700);
DISPLAY INVISIBLE (-1700 4700);
FORCEADD TAP..6
R 2
(-1700 4800);
FORCEPROP 3 LASTPIN (-1750 4800) SIG_NAME M_K_DQ<63>
J 0
(-1740 4810);
DISPLAY 0.659574 (-1740 4810);
PAINT MONO (-1740 4810);
DISPLAY INVISIBLE (-1740 4810);
FORCEPROP 1 LASTPIN (-1750 4800) BN 63
J 2
(-1700 4810);
DISPLAY 0.617021 (-1700 4810);
PAINT PINK (-1700 4810);
FORCEPROP 2 LAST CDS_LIB mstr_standard
J 2
(-1700 4800);
DISPLAY 0.787234 (-1700 4800);
PAINT MONO (-1700 4800);
DISPLAY INVISIBLE (-1700 4800);
FORCEPROP 1 LAST BODY_TYPE PLUMBING
J 2
(-1700 4750);
DISPLAY 1.234043 (-1700 4750);
PAINT GREEN (-1700 4750);
DISPLAY INVISIBLE (-1700 4750);
FORCEPROP 1 LAST HDL_TAP TRUE
J 2
(-2025 4675);
DISPLAY 1.234043 (-2025 4675);
PAINT GREEN (-2025 4675);
DISPLAY INVISIBLE (-2025 4675);
FORCEPROP 1 LAST PATH I48
J 2
(-1700 4800);
DISPLAY 0.936170 (-1700 4800);
PAINT GREEN (-1700 4800);
DISPLAY INVISIBLE (-1700 4800);
FORCEADD TAP..6
R 2
(-1700 4850);
FORCEPROP 3 LASTPIN (-1750 4850) SIG_NAME M_K_DQ<62>
J 0
(-1740 4860);
DISPLAY 0.659574 (-1740 4860);
PAINT MONO (-1740 4860);
DISPLAY INVISIBLE (-1740 4860);
FORCEPROP 1 LASTPIN (-1750 4850) BN 62
J 2
(-1700 4860);
DISPLAY 0.617021 (-1700 4860);
PAINT PINK (-1700 4860);
FORCEPROP 2 LAST CDS_LIB mstr_standard
J 2
(-1700 4850);
DISPLAY 0.787234 (-1700 4850);
PAINT MONO (-1700 4850);
DISPLAY INVISIBLE (-1700 4850);
FORCEPROP 1 LAST BODY_TYPE PLUMBING
J 2
(-1700 4800);
DISPLAY 1.234043 (-1700 4800);
PAINT GREEN (-1700 4800);
DISPLAY INVISIBLE (-1700 4800);
FORCEPROP 1 LAST HDL_TAP TRUE
J 2
(-2025 4725);
DISPLAY 1.234043 (-2025 4725);
PAINT GREEN (-2025 4725);
DISPLAY INVISIBLE (-2025 4725);
FORCEPROP 1 LAST PATH I49
J 2
(-1700 4850);
DISPLAY 0.936170 (-1700 4850);
PAINT GREEN (-1700 4850);
DISPLAY INVISIBLE (-1700 4850);
FORCEADD TAP..6
R 2
(900 5050);
FORCEPROP 3 LASTPIN (850 5050) SIG_NAME M_K_DQS_DN<16>
J 0
(860 5060);
DISPLAY 0.659574 (860 5060);
PAINT MONO (860 5060);
DISPLAY INVISIBLE (860 5060);
FORCEPROP 1 LASTPIN (850 5050) BN 16
J 2
(900 5060);
DISPLAY 0.617021 (900 5060);
PAINT PINK (900 5060);
FORCEPROP 2 LAST CDS_LIB mstr_standard
J 0
(900 5050);
DISPLAY 0.787234 (900 5050);
PAINT MONO (900 5050);
DISPLAY INVISIBLE (900 5050);
FORCEPROP 1 LAST BODY_TYPE PLUMBING
J 2
(900 5000);
DISPLAY 1.234043 (900 5000);
PAINT GREEN (900 5000);
DISPLAY INVISIBLE (900 5000);
FORCEPROP 1 LAST HDL_TAP TRUE
J 2
(575 4925);
DISPLAY 1.234043 (575 4925);
PAINT GREEN (575 4925);
DISPLAY INVISIBLE (575 4925);
FORCEPROP 1 LAST PATH I5
J 2
(900 5050);
DISPLAY 0.936170 (900 5050);
PAINT GREEN (900 5050);
DISPLAY INVISIBLE (900 5050);
FORCEADD TAP..6
R 2
(-1700 4450);
FORCEPROP 3 LASTPIN (-1750 4450) SIG_NAME M_K_DQ<54>
J 0
(-1740 4460);
DISPLAY 0.659574 (-1740 4460);
PAINT MONO (-1740 4460);
DISPLAY INVISIBLE (-1740 4460);
FORCEPROP 1 LASTPIN (-1750 4450) BN 54
J 2
(-1700 4460);
DISPLAY 0.617021 (-1700 4460);
PAINT PINK (-1700 4460);
FORCEPROP 2 LAST CDS_LIB mstr_standard
J 2
(-1700 4450);
DISPLAY 0.787234 (-1700 4450);
PAINT MONO (-1700 4450);
DISPLAY INVISIBLE (-1700 4450);
FORCEPROP 1 LAST BODY_TYPE PLUMBING
J 2
(-1700 4400);
DISPLAY 1.234043 (-1700 4400);
PAINT GREEN (-1700 4400);
DISPLAY INVISIBLE (-1700 4400);
FORCEPROP 1 LAST HDL_TAP TRUE
J 2
(-2025 4325);
DISPLAY 1.234043 (-2025 4325);
PAINT GREEN (-2025 4325);
DISPLAY INVISIBLE (-2025 4325);
FORCEPROP 1 LAST PATH I50
J 2
(-1700 4450);
DISPLAY 0.936170 (-1700 4450);
PAINT GREEN (-1700 4450);
DISPLAY INVISIBLE (-1700 4450);
FORCEADD TAP..6
R 2
(-1700 4500);
FORCEPROP 3 LASTPIN (-1750 4500) SIG_NAME M_K_DQ<57>
J 0
(-1740 4510);
DISPLAY 0.659574 (-1740 4510);
PAINT MONO (-1740 4510);
DISPLAY INVISIBLE (-1740 4510);
FORCEPROP 1 LASTPIN (-1750 4500) BN 57
J 2
(-1700 4510);
DISPLAY 0.617021 (-1700 4510);
PAINT PINK (-1700 4510);
FORCEPROP 2 LAST CDS_LIB mstr_standard
J 2
(-1700 4500);
DISPLAY 0.787234 (-1700 4500);
PAINT MONO (-1700 4500);
DISPLAY INVISIBLE (-1700 4500);
FORCEPROP 1 LAST BODY_TYPE PLUMBING
J 2
(-1700 4450);
DISPLAY 1.234043 (-1700 4450);
PAINT GREEN (-1700 4450);
DISPLAY INVISIBLE (-1700 4450);
FORCEPROP 1 LAST HDL_TAP TRUE
J 2
(-2025 4375);
DISPLAY 1.234043 (-2025 4375);
PAINT GREEN (-2025 4375);
DISPLAY INVISIBLE (-2025 4375);
FORCEPROP 1 LAST PATH I51
J 2
(-1700 4500);
DISPLAY 0.936170 (-1700 4500);
PAINT GREEN (-1700 4500);
DISPLAY INVISIBLE (-1700 4500);
FORCEADD TAP..6
R 2
(-1700 4600);
FORCEPROP 3 LASTPIN (-1750 4600) SIG_NAME M_K_DQ<59>
J 0
(-1740 4610);
DISPLAY 0.659574 (-1740 4610);
PAINT MONO (-1740 4610);
DISPLAY INVISIBLE (-1740 4610);
FORCEPROP 1 LASTPIN (-1750 4600) BN 59
J 2
(-1700 4610);
DISPLAY 0.617021 (-1700 4610);
PAINT PINK (-1700 4610);
FORCEPROP 2 LAST CDS_LIB mstr_standard
J 2
(-1700 4600);
DISPLAY 0.787234 (-1700 4600);
PAINT MONO (-1700 4600);
DISPLAY INVISIBLE (-1700 4600);
FORCEPROP 1 LAST BODY_TYPE PLUMBING
J 2
(-1700 4550);
DISPLAY 1.234043 (-1700 4550);
PAINT GREEN (-1700 4550);
DISPLAY INVISIBLE (-1700 4550);
FORCEPROP 1 LAST HDL_TAP TRUE
J 2
(-2025 4475);
DISPLAY 1.234043 (-2025 4475);
PAINT GREEN (-2025 4475);
DISPLAY INVISIBLE (-2025 4475);
FORCEPROP 1 LAST PATH I52
J 2
(-1700 4600);
DISPLAY 0.936170 (-1700 4600);
PAINT GREEN (-1700 4600);
DISPLAY INVISIBLE (-1700 4600);
FORCEADD TAP..6
R 2
(-1700 4550);
FORCEPROP 3 LASTPIN (-1750 4550) SIG_NAME M_K_DQ<56>
J 0
(-1740 4560);
DISPLAY 0.659574 (-1740 4560);
PAINT MONO (-1740 4560);
DISPLAY INVISIBLE (-1740 4560);
FORCEPROP 1 LASTPIN (-1750 4550) BN 56
J 2
(-1700 4560);
DISPLAY 0.617021 (-1700 4560);
PAINT PINK (-1700 4560);
FORCEPROP 2 LAST CDS_LIB mstr_standard
J 2
(-1700 4550);
DISPLAY 0.787234 (-1700 4550);
PAINT MONO (-1700 4550);
DISPLAY INVISIBLE (-1700 4550);
FORCEPROP 1 LAST BODY_TYPE PLUMBING
J 2
(-1700 4500);
DISPLAY 1.234043 (-1700 4500);
PAINT GREEN (-1700 4500);
DISPLAY INVISIBLE (-1700 4500);
FORCEPROP 1 LAST HDL_TAP TRUE
J 2
(-2025 4425);
DISPLAY 1.234043 (-2025 4425);
PAINT GREEN (-2025 4425);
DISPLAY INVISIBLE (-2025 4425);
FORCEPROP 1 LAST PATH I53
J 2
(-1700 4550);
DISPLAY 0.936170 (-1700 4550);
PAINT GREEN (-1700 4550);
DISPLAY INVISIBLE (-1700 4550);
FORCEADD TAP..6
R 2
(-1700 4650);
FORCEPROP 3 LASTPIN (-1750 4650) SIG_NAME M_K_DQ<58>
J 0
(-1740 4660);
DISPLAY 0.659574 (-1740 4660);
PAINT MONO (-1740 4660);
DISPLAY INVISIBLE (-1740 4660);
FORCEPROP 1 LASTPIN (-1750 4650) BN 58
J 2
(-1700 4660);
DISPLAY 0.617021 (-1700 4660);
PAINT PINK (-1700 4660);
FORCEPROP 2 LAST CDS_LIB mstr_standard
J 2
(-1700 4650);
DISPLAY 0.787234 (-1700 4650);
PAINT MONO (-1700 4650);
DISPLAY INVISIBLE (-1700 4650);
FORCEPROP 1 LAST BODY_TYPE PLUMBING
J 2
(-1700 4600);
DISPLAY 1.234043 (-1700 4600);
PAINT GREEN (-1700 4600);
DISPLAY INVISIBLE (-1700 4600);
FORCEPROP 1 LAST HDL_TAP TRUE
J 2
(-2025 4525);
DISPLAY 1.234043 (-2025 4525);
PAINT GREEN (-2025 4525);
DISPLAY INVISIBLE (-2025 4525);
FORCEPROP 1 LAST PATH I54
J 2
(-1700 4650);
DISPLAY 0.936170 (-1700 4650);
PAINT GREEN (-1700 4650);
DISPLAY INVISIBLE (-1700 4650);
FORCEADD TAP..6
R 2
(-1700 4200);
FORCEPROP 3 LASTPIN (-1750 4200) SIG_NAME M_K_DQ<51>
J 0
(-1740 4210);
DISPLAY 0.659574 (-1740 4210);
PAINT MONO (-1740 4210);
DISPLAY INVISIBLE (-1740 4210);
FORCEPROP 1 LASTPIN (-1750 4200) BN 51
J 2
(-1700 4210);
DISPLAY 0.617021 (-1700 4210);
PAINT PINK (-1700 4210);
FORCEPROP 2 LAST CDS_LIB mstr_standard
J 2
(-1700 4200);
DISPLAY 0.787234 (-1700 4200);
PAINT MONO (-1700 4200);
DISPLAY INVISIBLE (-1700 4200);
FORCEPROP 1 LAST BODY_TYPE PLUMBING
J 2
(-1700 4150);
DISPLAY 1.234043 (-1700 4150);
PAINT GREEN (-1700 4150);
DISPLAY INVISIBLE (-1700 4150);
FORCEPROP 1 LAST HDL_TAP TRUE
J 2
(-2025 4075);
DISPLAY 1.234043 (-2025 4075);
PAINT GREEN (-2025 4075);
DISPLAY INVISIBLE (-2025 4075);
FORCEPROP 1 LAST PATH I55
J 2
(-1700 4200);
DISPLAY 0.936170 (-1700 4200);
PAINT GREEN (-1700 4200);
DISPLAY INVISIBLE (-1700 4200);
FORCEADD TAP..6
R 2
(-1700 4250);
FORCEPROP 3 LASTPIN (-1750 4250) SIG_NAME M_K_DQ<50>
J 0
(-1740 4260);
DISPLAY 0.659574 (-1740 4260);
PAINT MONO (-1740 4260);
DISPLAY INVISIBLE (-1740 4260);
FORCEPROP 1 LASTPIN (-1750 4250) BN 50
J 2
(-1700 4260);
DISPLAY 0.617021 (-1700 4260);
PAINT PINK (-1700 4260);
FORCEPROP 2 LAST CDS_LIB mstr_standard
J 2
(-1700 4250);
DISPLAY 0.787234 (-1700 4250);
PAINT MONO (-1700 4250);
DISPLAY INVISIBLE (-1700 4250);
FORCEPROP 1 LAST BODY_TYPE PLUMBING
J 2
(-1700 4200);
DISPLAY 1.234043 (-1700 4200);
PAINT GREEN (-1700 4200);
DISPLAY INVISIBLE (-1700 4200);
FORCEPROP 1 LAST HDL_TAP TRUE
J 2
(-2025 4125);
DISPLAY 1.234043 (-2025 4125);
PAINT GREEN (-2025 4125);
DISPLAY INVISIBLE (-2025 4125);
FORCEPROP 1 LAST PATH I56
J 2
(-1700 4250);
DISPLAY 0.936170 (-1700 4250);
PAINT GREEN (-1700 4250);
DISPLAY INVISIBLE (-1700 4250);
FORCEADD TAP..6
R 2
(-1700 4300);
FORCEPROP 3 LASTPIN (-1750 4300) SIG_NAME M_K_DQ<53>
J 0
(-1740 4310);
DISPLAY 0.659574 (-1740 4310);
PAINT MONO (-1740 4310);
DISPLAY INVISIBLE (-1740 4310);
FORCEPROP 1 LASTPIN (-1750 4300) BN 53
J 2
(-1700 4310);
DISPLAY 0.617021 (-1700 4310);
PAINT PINK (-1700 4310);
FORCEPROP 2 LAST CDS_LIB mstr_standard
J 2
(-1700 4300);
DISPLAY 0.787234 (-1700 4300);
PAINT MONO (-1700 4300);
DISPLAY INVISIBLE (-1700 4300);
FORCEPROP 1 LAST BODY_TYPE PLUMBING
J 2
(-1700 4250);
DISPLAY 1.234043 (-1700 4250);
PAINT GREEN (-1700 4250);
DISPLAY INVISIBLE (-1700 4250);
FORCEPROP 1 LAST HDL_TAP TRUE
J 2
(-2025 4175);
DISPLAY 1.234043 (-2025 4175);
PAINT GREEN (-2025 4175);
DISPLAY INVISIBLE (-2025 4175);
FORCEPROP 1 LAST PATH I57
J 2
(-1700 4300);
DISPLAY 0.936170 (-1700 4300);
PAINT GREEN (-1700 4300);
DISPLAY INVISIBLE (-1700 4300);
FORCEADD TAP..6
R 2
(-1700 4400);
FORCEPROP 3 LASTPIN (-1750 4400) SIG_NAME M_K_DQ<55>
J 0
(-1740 4410);
DISPLAY 0.659574 (-1740 4410);
PAINT MONO (-1740 4410);
DISPLAY INVISIBLE (-1740 4410);
FORCEPROP 1 LASTPIN (-1750 4400) BN 55
J 2
(-1700 4410);
DISPLAY 0.617021 (-1700 4410);
PAINT PINK (-1700 4410);
FORCEPROP 2 LAST CDS_LIB mstr_standard
J 2
(-1700 4400);
DISPLAY 0.787234 (-1700 4400);
PAINT MONO (-1700 4400);
DISPLAY INVISIBLE (-1700 4400);
FORCEPROP 1 LAST BODY_TYPE PLUMBING
J 2
(-1700 4350);
DISPLAY 1.234043 (-1700 4350);
PAINT GREEN (-1700 4350);
DISPLAY INVISIBLE (-1700 4350);
FORCEPROP 1 LAST HDL_TAP TRUE
J 2
(-2025 4275);
DISPLAY 1.234043 (-2025 4275);
PAINT GREEN (-2025 4275);
DISPLAY INVISIBLE (-2025 4275);
FORCEPROP 1 LAST PATH I58
J 2
(-1700 4400);
DISPLAY 0.936170 (-1700 4400);
PAINT GREEN (-1700 4400);
DISPLAY INVISIBLE (-1700 4400);
FORCEADD TAP..6
R 2
(-1700 4350);
FORCEPROP 3 LASTPIN (-1750 4350) SIG_NAME M_K_DQ<52>
J 0
(-1740 4360);
DISPLAY 0.659574 (-1740 4360);
PAINT MONO (-1740 4360);
DISPLAY INVISIBLE (-1740 4360);
FORCEPROP 1 LASTPIN (-1750 4350) BN 52
J 2
(-1700 4360);
DISPLAY 0.617021 (-1700 4360);
PAINT PINK (-1700 4360);
FORCEPROP 2 LAST CDS_LIB mstr_standard
J 2
(-1700 4350);
DISPLAY 0.787234 (-1700 4350);
PAINT MONO (-1700 4350);
DISPLAY INVISIBLE (-1700 4350);
FORCEPROP 1 LAST BODY_TYPE PLUMBING
J 2
(-1700 4300);
DISPLAY 1.234043 (-1700 4300);
PAINT GREEN (-1700 4300);
DISPLAY INVISIBLE (-1700 4300);
FORCEPROP 1 LAST HDL_TAP TRUE
J 2
(-2025 4225);
DISPLAY 1.234043 (-2025 4225);
PAINT GREEN (-2025 4225);
DISPLAY INVISIBLE (-2025 4225);
FORCEPROP 1 LAST PATH I59
J 2
(-1700 4350);
DISPLAY 0.936170 (-1700 4350);
PAINT GREEN (-1700 4350);
DISPLAY INVISIBLE (-1700 4350);
FORCEADD TAP..6
R 2
(900 4950);
FORCEPROP 3 LASTPIN (850 4950) SIG_NAME M_K_DQS_DN<15>
J 0
(860 4960);
DISPLAY 0.659574 (860 4960);
PAINT MONO (860 4960);
DISPLAY INVISIBLE (860 4960);
FORCEPROP 1 LASTPIN (850 4950) BN 15
J 2
(900 4960);
DISPLAY 0.617021 (900 4960);
PAINT PINK (900 4960);
FORCEPROP 2 LAST CDS_LIB mstr_standard
J 0
(900 4950);
DISPLAY 0.787234 (900 4950);
PAINT MONO (900 4950);
DISPLAY INVISIBLE (900 4950);
FORCEPROP 1 LAST BODY_TYPE PLUMBING
J 2
(900 4900);
DISPLAY 1.234043 (900 4900);
PAINT GREEN (900 4900);
DISPLAY INVISIBLE (900 4900);
FORCEPROP 1 LAST HDL_TAP TRUE
J 2
(575 4825);
DISPLAY 1.234043 (575 4825);
PAINT GREEN (575 4825);
DISPLAY INVISIBLE (575 4825);
FORCEPROP 1 LAST PATH I6
J 2
(900 4950);
DISPLAY 0.936170 (900 4950);
PAINT GREEN (900 4950);
DISPLAY INVISIBLE (900 4950);
FORCEADD TAP..6
R 2
(-1700 3900);
FORCEPROP 3 LASTPIN (-1750 3900) SIG_NAME M_K_DQ<45>
J 0
(-1740 3910);
DISPLAY 0.659574 (-1740 3910);
PAINT MONO (-1740 3910);
DISPLAY INVISIBLE (-1740 3910);
FORCEPROP 1 LASTPIN (-1750 3900) BN 45
J 2
(-1700 3910);
DISPLAY 0.617021 (-1700 3910);
PAINT PINK (-1700 3910);
FORCEPROP 2 LAST CDS_LIB mstr_standard
J 2
(-1700 3900);
DISPLAY 0.787234 (-1700 3900);
PAINT MONO (-1700 3900);
DISPLAY INVISIBLE (-1700 3900);
FORCEPROP 1 LAST BODY_TYPE PLUMBING
J 2
(-1700 3850);
DISPLAY 1.234043 (-1700 3850);
PAINT GREEN (-1700 3850);
DISPLAY INVISIBLE (-1700 3850);
FORCEPROP 1 LAST HDL_TAP TRUE
J 2
(-2025 3775);
DISPLAY 1.234043 (-2025 3775);
PAINT GREEN (-2025 3775);
DISPLAY INVISIBLE (-2025 3775);
FORCEPROP 1 LAST PATH I60
J 2
(-1700 3900);
DISPLAY 0.936170 (-1700 3900);
PAINT GREEN (-1700 3900);
DISPLAY INVISIBLE (-1700 3900);
FORCEADD TAP..6
R 2
(-1700 3950);
FORCEPROP 3 LASTPIN (-1750 3950) SIG_NAME M_K_DQ<44>
J 0
(-1740 3960);
DISPLAY 0.659574 (-1740 3960);
PAINT MONO (-1740 3960);
DISPLAY INVISIBLE (-1740 3960);
FORCEPROP 1 LASTPIN (-1750 3950) BN 44
J 2
(-1700 3960);
DISPLAY 0.617021 (-1700 3960);
PAINT PINK (-1700 3960);
FORCEPROP 2 LAST CDS_LIB mstr_standard
J 2
(-1700 3950);
DISPLAY 0.787234 (-1700 3950);
PAINT MONO (-1700 3950);
DISPLAY INVISIBLE (-1700 3950);
FORCEPROP 1 LAST BODY_TYPE PLUMBING
J 2
(-1700 3900);
DISPLAY 1.234043 (-1700 3900);
PAINT GREEN (-1700 3900);
DISPLAY INVISIBLE (-1700 3900);
FORCEPROP 1 LAST HDL_TAP TRUE
J 2
(-2025 3825);
DISPLAY 1.234043 (-2025 3825);
PAINT GREEN (-2025 3825);
DISPLAY INVISIBLE (-2025 3825);
FORCEPROP 1 LAST PATH I61
J 2
(-1700 3950);
DISPLAY 0.936170 (-1700 3950);
PAINT GREEN (-1700 3950);
DISPLAY INVISIBLE (-1700 3950);
FORCEADD TAP..6
R 2
(-1700 4000);
FORCEPROP 3 LASTPIN (-1750 4000) SIG_NAME M_K_DQ<47>
J 0
(-1740 4010);
DISPLAY 0.659574 (-1740 4010);
PAINT MONO (-1740 4010);
DISPLAY INVISIBLE (-1740 4010);
FORCEPROP 1 LASTPIN (-1750 4000) BN 47
J 2
(-1700 4010);
DISPLAY 0.617021 (-1700 4010);
PAINT PINK (-1700 4010);
FORCEPROP 2 LAST CDS_LIB mstr_standard
J 2
(-1700 4000);
DISPLAY 0.787234 (-1700 4000);
PAINT MONO (-1700 4000);
DISPLAY INVISIBLE (-1700 4000);
FORCEPROP 1 LAST BODY_TYPE PLUMBING
J 2
(-1700 3950);
DISPLAY 1.234043 (-1700 3950);
PAINT GREEN (-1700 3950);
DISPLAY INVISIBLE (-1700 3950);
FORCEPROP 1 LAST HDL_TAP TRUE
J 2
(-2025 3875);
DISPLAY 1.234043 (-2025 3875);
PAINT GREEN (-2025 3875);
DISPLAY INVISIBLE (-2025 3875);
FORCEPROP 1 LAST PATH I62
J 2
(-1700 4000);
DISPLAY 0.936170 (-1700 4000);
PAINT GREEN (-1700 4000);
DISPLAY INVISIBLE (-1700 4000);
FORCEADD TAP..6
R 2
(-1700 4100);
FORCEPROP 3 LASTPIN (-1750 4100) SIG_NAME M_K_DQ<49>
J 0
(-1740 4110);
DISPLAY 0.659574 (-1740 4110);
PAINT MONO (-1740 4110);
DISPLAY INVISIBLE (-1740 4110);
FORCEPROP 1 LASTPIN (-1750 4100) BN 49
J 2
(-1700 4110);
DISPLAY 0.617021 (-1700 4110);
PAINT PINK (-1700 4110);
FORCEPROP 2 LAST CDS_LIB mstr_standard
J 2
(-1700 4100);
DISPLAY 0.787234 (-1700 4100);
PAINT MONO (-1700 4100);
DISPLAY INVISIBLE (-1700 4100);
FORCEPROP 1 LAST BODY_TYPE PLUMBING
J 2
(-1700 4050);
DISPLAY 1.234043 (-1700 4050);
PAINT GREEN (-1700 4050);
DISPLAY INVISIBLE (-1700 4050);
FORCEPROP 1 LAST HDL_TAP TRUE
J 2
(-2025 3975);
DISPLAY 1.234043 (-2025 3975);
PAINT GREEN (-2025 3975);
DISPLAY INVISIBLE (-2025 3975);
FORCEPROP 1 LAST PATH I63
J 2
(-1700 4100);
DISPLAY 0.936170 (-1700 4100);
PAINT GREEN (-1700 4100);
DISPLAY INVISIBLE (-1700 4100);
FORCEADD TAP..6
R 2
(-1700 4050);
FORCEPROP 3 LASTPIN (-1750 4050) SIG_NAME M_K_DQ<46>
J 0
(-1740 4060);
DISPLAY 0.659574 (-1740 4060);
PAINT MONO (-1740 4060);
DISPLAY INVISIBLE (-1740 4060);
FORCEPROP 1 LASTPIN (-1750 4050) BN 46
J 2
(-1700 4060);
DISPLAY 0.617021 (-1700 4060);
PAINT PINK (-1700 4060);
FORCEPROP 2 LAST CDS_LIB mstr_standard
J 2
(-1700 4050);
DISPLAY 0.787234 (-1700 4050);
PAINT MONO (-1700 4050);
DISPLAY INVISIBLE (-1700 4050);
FORCEPROP 1 LAST BODY_TYPE PLUMBING
J 2
(-1700 4000);
DISPLAY 1.234043 (-1700 4000);
PAINT GREEN (-1700 4000);
DISPLAY INVISIBLE (-1700 4000);
FORCEPROP 1 LAST HDL_TAP TRUE
J 2
(-2025 3925);
DISPLAY 1.234043 (-2025 3925);
PAINT GREEN (-2025 3925);
DISPLAY INVISIBLE (-2025 3925);
FORCEPROP 1 LAST PATH I64
J 2
(-1700 4050);
DISPLAY 0.936170 (-1700 4050);
PAINT GREEN (-1700 4050);
DISPLAY INVISIBLE (-1700 4050);
FORCEADD TAP..6
R 2
(-1700 4150);
FORCEPROP 3 LASTPIN (-1750 4150) SIG_NAME M_K_DQ<48>
J 0
(-1740 4160);
DISPLAY 0.659574 (-1740 4160);
PAINT MONO (-1740 4160);
DISPLAY INVISIBLE (-1740 4160);
FORCEPROP 1 LASTPIN (-1750 4150) BN 48
J 2
(-1700 4160);
DISPLAY 0.617021 (-1700 4160);
PAINT PINK (-1700 4160);
FORCEPROP 2 LAST CDS_LIB mstr_standard
J 2
(-1700 4150);
DISPLAY 0.787234 (-1700 4150);
PAINT MONO (-1700 4150);
DISPLAY INVISIBLE (-1700 4150);
FORCEPROP 1 LAST BODY_TYPE PLUMBING
J 2
(-1700 4100);
DISPLAY 1.234043 (-1700 4100);
PAINT GREEN (-1700 4100);
DISPLAY INVISIBLE (-1700 4100);
FORCEPROP 1 LAST HDL_TAP TRUE
J 2
(-2025 4025);
DISPLAY 1.234043 (-2025 4025);
PAINT GREEN (-2025 4025);
DISPLAY INVISIBLE (-2025 4025);
FORCEPROP 1 LAST PATH I65
J 2
(-1700 4150);
DISPLAY 0.936170 (-1700 4150);
PAINT GREEN (-1700 4150);
DISPLAY INVISIBLE (-1700 4150);
FORCEADD SCONN288_H44441004..2
(0 4350);
FORCEPROP 1 LAST LOCATION J1B1
J 0
(-400 5450);
DISPLAY 0.617021 (-400 5450);
PAINT AQUA (-400 5450);
FORCEPROP 1 LAST PART_NUMBER H44441-004
J 0
(-400 3250);
DISPLAY 0.617021 (-400 3250);
PAINT BLUE (-400 3250);
FORCEPROP 1 LAST MATERIAL SCONN
J 0
(-400 5400);
DISPLAY 0.617021 (-400 5400);
PAINT SKYBLUE (-400 5400);
FORCEPROP 2 LASTPIN (450 5200) $PN 51
J 0
(460 5210);
DISPLAY 0.617021 (460 5210);
PAINT ORANGE (460 5210);
FORCEPROP 2 LASTPIN (450 5150) $PN 52
J 0
(460 5160);
DISPLAY 0.617021 (460 5160);
PAINT ORANGE (460 5160);
FORCEPROP 2 LASTPIN (450 5100) $PN 132
J 0
(460 5110);
DISPLAY 0.617021 (460 5110);
PAINT ORANGE (460 5110);
FORCEPROP 2 LASTPIN (450 5050) $PN 133
J 0
(460 5060);
DISPLAY 0.617021 (460 5060);
PAINT ORANGE (460 5060);
FORCEPROP 2 LASTPIN (450 5000) $PN 121
J 0
(460 5010);
DISPLAY 0.617021 (460 5010);
PAINT ORANGE (460 5010);
FORCEPROP 2 LASTPIN (450 4950) $PN 122
J 0
(460 4960);
DISPLAY 0.617021 (460 4960);
PAINT ORANGE (460 4960);
FORCEPROP 2 LASTPIN (450 4900) $PN 110
J 0
(460 4910);
DISPLAY 0.617021 (460 4910);
PAINT ORANGE (460 4910);
FORCEPROP 2 LASTPIN (450 4850) $PN 111
J 0
(460 4860);
DISPLAY 0.617021 (460 4860);
PAINT ORANGE (460 4860);
FORCEPROP 2 LASTPIN (450 4800) $PN 99
J 0
(460 4810);
DISPLAY 0.617021 (460 4810);
PAINT ORANGE (460 4810);
FORCEPROP 2 LASTPIN (450 4750) $PN 100
J 0
(460 4760);
DISPLAY 0.617021 (460 4760);
PAINT ORANGE (460 4760);
FORCEPROP 2 LASTPIN (450 4700) $PN 40
J 0
(460 4710);
DISPLAY 0.617021 (460 4710);
PAINT ORANGE (460 4710);
FORCEPROP 2 LASTPIN (450 4650) $PN 41
J 0
(460 4660);
DISPLAY 0.617021 (460 4660);
PAINT ORANGE (460 4660);
FORCEPROP 2 LASTPIN (450 4600) $PN 29
J 0
(460 4610);
DISPLAY 0.617021 (460 4610);
PAINT ORANGE (460 4610);
FORCEPROP 2 LASTPIN (450 4550) $PN 30
J 0
(460 4560);
DISPLAY 0.617021 (460 4560);
PAINT ORANGE (460 4560);
FORCEPROP 2 LASTPIN (450 4500) $PN 18
J 0
(460 4510);
DISPLAY 0.617021 (460 4510);
PAINT ORANGE (460 4510);
FORCEPROP 2 LASTPIN (450 4450) $PN 19
J 0
(460 4460);
DISPLAY 0.617021 (460 4460);
PAINT ORANGE (460 4460);
FORCEPROP 2 LASTPIN (450 4400) $PN 7
J 0
(460 4410);
DISPLAY 0.617021 (460 4410);
PAINT ORANGE (460 4410);
FORCEPROP 2 LASTPIN (450 4350) $PN 8
J 0
(460 4360);
DISPLAY 0.617021 (460 4360);
PAINT ORANGE (460 4360);
FORCEPROP 2 LASTPIN (450 4300) $PN 197
J 0
(460 4310);
DISPLAY 0.617021 (460 4310);
PAINT ORANGE (460 4310);
FORCEPROP 2 LASTPIN (450 4250) $PN 196
J 0
(460 4260);
DISPLAY 0.617021 (460 4260);
PAINT ORANGE (460 4260);
FORCEPROP 2 LASTPIN (450 4200) $PN 278
J 0
(460 4210);
DISPLAY 0.617021 (460 4210);
PAINT ORANGE (460 4210);
FORCEPROP 2 LASTPIN (450 4150) $PN 277
J 0
(460 4160);
DISPLAY 0.617021 (460 4160);
PAINT ORANGE (460 4160);
FORCEPROP 2 LASTPIN (450 4100) $PN 267
J 0
(460 4110);
DISPLAY 0.617021 (460 4110);
PAINT ORANGE (460 4110);
FORCEPROP 2 LASTPIN (450 4050) $PN 266
J 0
(460 4060);
DISPLAY 0.617021 (460 4060);
PAINT ORANGE (460 4060);
FORCEPROP 2 LASTPIN (450 4000) $PN 256
J 0
(460 4010);
DISPLAY 0.617021 (460 4010);
PAINT ORANGE (460 4010);
FORCEPROP 2 LASTPIN (450 3950) $PN 255
J 0
(460 3960);
DISPLAY 0.617021 (460 3960);
PAINT ORANGE (460 3960);
FORCEPROP 2 LASTPIN (450 3900) $PN 245
J 0
(460 3910);
DISPLAY 0.617021 (460 3910);
PAINT ORANGE (460 3910);
FORCEPROP 2 LASTPIN (450 3850) $PN 244
J 0
(460 3860);
DISPLAY 0.617021 (460 3860);
PAINT ORANGE (460 3860);
FORCEPROP 2 LASTPIN (450 3800) $PN 186
J 0
(460 3810);
DISPLAY 0.617021 (460 3810);
PAINT ORANGE (460 3810);
FORCEPROP 2 LASTPIN (450 3750) $PN 185
J 0
(460 3760);
DISPLAY 0.617021 (460 3760);
PAINT ORANGE (460 3760);
FORCEPROP 2 LASTPIN (450 3700) $PN 175
J 0
(460 3710);
DISPLAY 0.617021 (460 3710);
PAINT ORANGE (460 3710);
FORCEPROP 2 LASTPIN (450 3650) $PN 174
J 0
(460 3660);
DISPLAY 0.617021 (460 3660);
PAINT ORANGE (460 3660);
FORCEPROP 2 LASTPIN (450 3600) $PN 164
J 0
(460 3610);
DISPLAY 0.617021 (460 3610);
PAINT ORANGE (460 3610);
FORCEPROP 2 LASTPIN (450 3550) $PN 163
J 0
(460 3560);
DISPLAY 0.617021 (460 3560);
PAINT ORANGE (460 3560);
FORCEPROP 2 LASTPIN (450 3500) $PN 153
J 0
(460 3510);
DISPLAY 0.617021 (460 3510);
PAINT ORANGE (460 3510);
FORCEPROP 2 LASTPIN (450 3450) $PN 152
J 0
(460 3460);
DISPLAY 0.617021 (460 3460);
PAINT ORANGE (460 3460);
FORCEPROP 1 LAST PACK_TYPE PIP
J 0
(-400 5500);
PAINT SKYBLUE (-400 5500);
DISPLAY INVISIBLE (-400 5500);
FORCEPROP 2 LAST BOM_COST MEM
J 0
(0 4350);
PAINT ORANGE (0 4350);
DISPLAY INVISIBLE (0 4350);
FORCEPROP 2 LAST CDS_LIB mstr_sconn
J 0
(0 4350);
PAINT ORANGE (0 4350);
DISPLAY INVISIBLE (0 4350);
FORCEPROP 2 LAST SEC_TYPE PIP
J 0
(-400 5500);
DISPLAY 1.021277 (-400 5500);
PAINT ORANGE (-400 5500);
DISPLAY INVISIBLE (-400 5500);
FORCEPROP 2 LAST SEC 2
J 0
(-400 5500);
DISPLAY 0.680851 (-400 5500);
PAINT MONO (-400 5500);
DISPLAY INVISIBLE (-400 5500);
FORCEPROP 2 LAST CDS_LOCATION J1B1
J 0
(-400 5450);
DISPLAY 0.617021 (-400 5450);
PAINT AQUA (-400 5450);
DISPLAY INVISIBLE (-400 5450);
FORCEPROP 1 LAST PATH I66
J 0
(0 5400);
PAINT GREEN (0 5400);
DISPLAY INVISIBLE (0 5400);
FORCEPROP 2 LAST ROOM DDR4_CH_K
J 0
(-400 5550);
PAINT ORANGE (-400 5550);
DISPLAY INVISIBLE (-400 5550);
FORCEADD TAP..6
R 2
(-1700 3750);
FORCEPROP 3 LASTPIN (-1750 3750) SIG_NAME M_K_DQ<40>
J 0
(-1740 3760);
DISPLAY 0.659574 (-1740 3760);
PAINT MONO (-1740 3760);
DISPLAY INVISIBLE (-1740 3760);
FORCEPROP 1 LASTPIN (-1750 3750) BN 40
J 2
(-1700 3760);
DISPLAY 0.617021 (-1700 3760);
PAINT PINK (-1700 3760);
FORCEPROP 2 LAST CDS_LIB mstr_standard
J 2
(-1700 3750);
DISPLAY 0.787234 (-1700 3750);
PAINT MONO (-1700 3750);
DISPLAY INVISIBLE (-1700 3750);
FORCEPROP 1 LAST BODY_TYPE PLUMBING
J 2
(-1700 3700);
DISPLAY 1.234043 (-1700 3700);
PAINT GREEN (-1700 3700);
DISPLAY INVISIBLE (-1700 3700);
FORCEPROP 1 LAST HDL_TAP TRUE
J 2
(-2025 3625);
DISPLAY 1.234043 (-2025 3625);
PAINT GREEN (-2025 3625);
DISPLAY INVISIBLE (-2025 3625);
FORCEPROP 1 LAST PATH I67
J 2
(-1700 3750);
DISPLAY 0.936170 (-1700 3750);
PAINT GREEN (-1700 3750);
DISPLAY INVISIBLE (-1700 3750);
FORCEADD TAP..6
R 2
(-1700 3650);
FORCEPROP 3 LASTPIN (-1750 3650) SIG_NAME M_K_DQ<38>
J 0
(-1740 3660);
DISPLAY 0.659574 (-1740 3660);
PAINT MONO (-1740 3660);
DISPLAY INVISIBLE (-1740 3660);
FORCEPROP 1 LASTPIN (-1750 3650) BN 38
J 2
(-1700 3660);
DISPLAY 0.617021 (-1700 3660);
PAINT PINK (-1700 3660);
FORCEPROP 2 LAST CDS_LIB mstr_standard
J 2
(-1700 3650);
DISPLAY 0.787234 (-1700 3650);
PAINT MONO (-1700 3650);
DISPLAY INVISIBLE (-1700 3650);
FORCEPROP 1 LAST BODY_TYPE PLUMBING
J 2
(-1700 3600);
DISPLAY 1.234043 (-1700 3600);
PAINT GREEN (-1700 3600);
DISPLAY INVISIBLE (-1700 3600);
FORCEPROP 1 LAST HDL_TAP TRUE
J 2
(-2025 3525);
DISPLAY 1.234043 (-2025 3525);
PAINT GREEN (-2025 3525);
DISPLAY INVISIBLE (-2025 3525);
FORCEPROP 1 LAST PATH I68
J 2
(-1700 3650);
DISPLAY 0.936170 (-1700 3650);
PAINT GREEN (-1700 3650);
DISPLAY INVISIBLE (-1700 3650);
FORCEADD TAP..6
R 2
(-1700 3700);
FORCEPROP 3 LASTPIN (-1750 3700) SIG_NAME M_K_DQ<41>
J 0
(-1740 3710);
DISPLAY 0.659574 (-1740 3710);
PAINT MONO (-1740 3710);
DISPLAY INVISIBLE (-1740 3710);
FORCEPROP 1 LASTPIN (-1750 3700) BN 41
J 2
(-1700 3710);
DISPLAY 0.617021 (-1700 3710);
PAINT PINK (-1700 3710);
FORCEPROP 2 LAST CDS_LIB mstr_standard
J 2
(-1700 3700);
DISPLAY 0.787234 (-1700 3700);
PAINT MONO (-1700 3700);
DISPLAY INVISIBLE (-1700 3700);
FORCEPROP 1 LAST BODY_TYPE PLUMBING
J 2
(-1700 3650);
DISPLAY 1.234043 (-1700 3650);
PAINT GREEN (-1700 3650);
DISPLAY INVISIBLE (-1700 3650);
FORCEPROP 1 LAST HDL_TAP TRUE
J 2
(-2025 3575);
DISPLAY 1.234043 (-2025 3575);
PAINT GREEN (-2025 3575);
DISPLAY INVISIBLE (-2025 3575);
FORCEPROP 1 LAST PATH I69
J 2
(-1700 3700);
DISPLAY 0.936170 (-1700 3700);
PAINT GREEN (-1700 3700);
DISPLAY INVISIBLE (-1700 3700);
FORCEADD TAP..6
R 2
(900 4850);
FORCEPROP 3 LASTPIN (850 4850) SIG_NAME M_K_DQS_DN<14>
J 0
(860 4860);
DISPLAY 0.659574 (860 4860);
PAINT MONO (860 4860);
DISPLAY INVISIBLE (860 4860);
FORCEPROP 1 LASTPIN (850 4850) BN 14
J 2
(900 4860);
DISPLAY 0.617021 (900 4860);
PAINT PINK (900 4860);
FORCEPROP 2 LAST CDS_LIB mstr_standard
J 0
(900 4850);
DISPLAY 0.787234 (900 4850);
PAINT MONO (900 4850);
DISPLAY INVISIBLE (900 4850);
FORCEPROP 1 LAST BODY_TYPE PLUMBING
J 2
(900 4800);
DISPLAY 1.234043 (900 4800);
PAINT GREEN (900 4800);
DISPLAY INVISIBLE (900 4800);
FORCEPROP 1 LAST HDL_TAP TRUE
J 2
(575 4725);
DISPLAY 1.234043 (575 4725);
PAINT GREEN (575 4725);
DISPLAY INVISIBLE (575 4725);
FORCEPROP 1 LAST PATH I7
J 2
(900 4850);
DISPLAY 0.936170 (900 4850);
PAINT GREEN (900 4850);
DISPLAY INVISIBLE (900 4850);
FORCEADD TAP..6
R 2
(-1700 3800);
FORCEPROP 3 LASTPIN (-1750 3800) SIG_NAME M_K_DQ<43>
J 0
(-1740 3810);
DISPLAY 0.659574 (-1740 3810);
PAINT MONO (-1740 3810);
DISPLAY INVISIBLE (-1740 3810);
FORCEPROP 1 LASTPIN (-1750 3800) BN 43
J 2
(-1700 3810);
DISPLAY 0.617021 (-1700 3810);
PAINT PINK (-1700 3810);
FORCEPROP 2 LAST CDS_LIB mstr_standard
J 2
(-1700 3800);
DISPLAY 0.787234 (-1700 3800);
PAINT MONO (-1700 3800);
DISPLAY INVISIBLE (-1700 3800);
FORCEPROP 1 LAST BODY_TYPE PLUMBING
J 2
(-1700 3750);
DISPLAY 1.234043 (-1700 3750);
PAINT GREEN (-1700 3750);
DISPLAY INVISIBLE (-1700 3750);
FORCEPROP 1 LAST HDL_TAP TRUE
J 2
(-2025 3675);
DISPLAY 1.234043 (-2025 3675);
PAINT GREEN (-2025 3675);
DISPLAY INVISIBLE (-2025 3675);
FORCEPROP 1 LAST PATH I70
J 2
(-1700 3800);
DISPLAY 0.936170 (-1700 3800);
PAINT GREEN (-1700 3800);
DISPLAY INVISIBLE (-1700 3800);
FORCEADD TAP..6
R 2
(-1700 3850);
FORCEPROP 3 LASTPIN (-1750 3850) SIG_NAME M_K_DQ<42>
J 0
(-1740 3860);
DISPLAY 0.659574 (-1740 3860);
PAINT MONO (-1740 3860);
DISPLAY INVISIBLE (-1740 3860);
FORCEPROP 1 LASTPIN (-1750 3850) BN 42
J 2
(-1700 3860);
DISPLAY 0.617021 (-1700 3860);
PAINT PINK (-1700 3860);
FORCEPROP 2 LAST CDS_LIB mstr_standard
J 2
(-1700 3850);
DISPLAY 0.787234 (-1700 3850);
PAINT MONO (-1700 3850);
DISPLAY INVISIBLE (-1700 3850);
FORCEPROP 1 LAST BODY_TYPE PLUMBING
J 2
(-1700 3800);
DISPLAY 1.234043 (-1700 3800);
PAINT GREEN (-1700 3800);
DISPLAY INVISIBLE (-1700 3800);
FORCEPROP 1 LAST HDL_TAP TRUE
J 2
(-2025 3725);
DISPLAY 1.234043 (-2025 3725);
PAINT GREEN (-2025 3725);
DISPLAY INVISIBLE (-2025 3725);
FORCEPROP 1 LAST PATH I71
J 2
(-1700 3850);
DISPLAY 0.936170 (-1700 3850);
PAINT GREEN (-1700 3850);
DISPLAY INVISIBLE (-1700 3850);
FORCEADD TAP..6
R 2
(-1700 3450);
FORCEPROP 3 LASTPIN (-1750 3450) SIG_NAME M_K_DQ<34>
J 0
(-1740 3460);
DISPLAY 0.659574 (-1740 3460);
PAINT MONO (-1740 3460);
DISPLAY INVISIBLE (-1740 3460);
FORCEPROP 1 LASTPIN (-1750 3450) BN 34
J 2
(-1700 3460);
DISPLAY 0.617021 (-1700 3460);
PAINT PINK (-1700 3460);
FORCEPROP 2 LAST CDS_LIB mstr_standard
J 2
(-1700 3450);
DISPLAY 0.787234 (-1700 3450);
PAINT MONO (-1700 3450);
DISPLAY INVISIBLE (-1700 3450);
FORCEPROP 1 LAST BODY_TYPE PLUMBING
J 2
(-1700 3400);
DISPLAY 1.234043 (-1700 3400);
PAINT GREEN (-1700 3400);
DISPLAY INVISIBLE (-1700 3400);
FORCEPROP 1 LAST HDL_TAP TRUE
J 2
(-2025 3325);
DISPLAY 1.234043 (-2025 3325);
PAINT GREEN (-2025 3325);
DISPLAY INVISIBLE (-2025 3325);
FORCEPROP 1 LAST PATH I72
J 2
(-1700 3450);
DISPLAY 0.936170 (-1700 3450);
PAINT GREEN (-1700 3450);
DISPLAY INVISIBLE (-1700 3450);
FORCEADD TAP..6
R 2
(-1700 3400);
FORCEPROP 3 LASTPIN (-1750 3400) SIG_NAME M_K_DQ<35>
J 0
(-1740 3410);
DISPLAY 0.659574 (-1740 3410);
PAINT MONO (-1740 3410);
DISPLAY INVISIBLE (-1740 3410);
FORCEPROP 1 LASTPIN (-1750 3400) BN 35
J 2
(-1700 3410);
DISPLAY 0.617021 (-1700 3410);
PAINT PINK (-1700 3410);
FORCEPROP 2 LAST CDS_LIB mstr_standard
J 2
(-1700 3400);
DISPLAY 0.787234 (-1700 3400);
PAINT MONO (-1700 3400);
DISPLAY INVISIBLE (-1700 3400);
FORCEPROP 1 LAST BODY_TYPE PLUMBING
J 2
(-1700 3350);
DISPLAY 1.234043 (-1700 3350);
PAINT GREEN (-1700 3350);
DISPLAY INVISIBLE (-1700 3350);
FORCEPROP 1 LAST HDL_TAP TRUE
J 2
(-2025 3275);
DISPLAY 1.234043 (-2025 3275);
PAINT GREEN (-2025 3275);
DISPLAY INVISIBLE (-2025 3275);
FORCEPROP 1 LAST PATH I73
J 2
(-1700 3400);
DISPLAY 0.936170 (-1700 3400);
PAINT GREEN (-1700 3400);
DISPLAY INVISIBLE (-1700 3400);
FORCEADD TAP..6
R 2
(-1700 3500);
FORCEPROP 3 LASTPIN (-1750 3500) SIG_NAME M_K_DQ<37>
J 0
(-1740 3510);
DISPLAY 0.659574 (-1740 3510);
PAINT MONO (-1740 3510);
DISPLAY INVISIBLE (-1740 3510);
FORCEPROP 1 LASTPIN (-1750 3500) BN 37
J 2
(-1700 3510);
DISPLAY 0.617021 (-1700 3510);
PAINT PINK (-1700 3510);
FORCEPROP 2 LAST CDS_LIB mstr_standard
J 2
(-1700 3500);
DISPLAY 0.787234 (-1700 3500);
PAINT MONO (-1700 3500);
DISPLAY INVISIBLE (-1700 3500);
FORCEPROP 1 LAST BODY_TYPE PLUMBING
J 2
(-1700 3450);
DISPLAY 1.234043 (-1700 3450);
PAINT GREEN (-1700 3450);
DISPLAY INVISIBLE (-1700 3450);
FORCEPROP 1 LAST HDL_TAP TRUE
J 2
(-2025 3375);
DISPLAY 1.234043 (-2025 3375);
PAINT GREEN (-2025 3375);
DISPLAY INVISIBLE (-2025 3375);
FORCEPROP 1 LAST PATH I74
J 2
(-1700 3500);
DISPLAY 0.936170 (-1700 3500);
PAINT GREEN (-1700 3500);
DISPLAY INVISIBLE (-1700 3500);
FORCEADD TAP..6
R 2
(-1700 3550);
FORCEPROP 3 LASTPIN (-1750 3550) SIG_NAME M_K_DQ<36>
J 0
(-1740 3560);
DISPLAY 0.659574 (-1740 3560);
PAINT MONO (-1740 3560);
DISPLAY INVISIBLE (-1740 3560);
FORCEPROP 1 LASTPIN (-1750 3550) BN 36
J 2
(-1700 3560);
DISPLAY 0.617021 (-1700 3560);
PAINT PINK (-1700 3560);
FORCEPROP 2 LAST CDS_LIB mstr_standard
J 2
(-1700 3550);
DISPLAY 0.787234 (-1700 3550);
PAINT MONO (-1700 3550);
DISPLAY INVISIBLE (-1700 3550);
FORCEPROP 1 LAST BODY_TYPE PLUMBING
J 2
(-1700 3500);
DISPLAY 1.234043 (-1700 3500);
PAINT GREEN (-1700 3500);
DISPLAY INVISIBLE (-1700 3500);
FORCEPROP 1 LAST HDL_TAP TRUE
J 2
(-2025 3425);
DISPLAY 1.234043 (-2025 3425);
PAINT GREEN (-2025 3425);
DISPLAY INVISIBLE (-2025 3425);
FORCEPROP 1 LAST PATH I75
J 2
(-1700 3550);
DISPLAY 0.936170 (-1700 3550);
PAINT GREEN (-1700 3550);
DISPLAY INVISIBLE (-1700 3550);
FORCEADD TAP..6
R 2
(-1700 3600);
FORCEPROP 3 LASTPIN (-1750 3600) SIG_NAME M_K_DQ<39>
J 0
(-1740 3610);
DISPLAY 0.659574 (-1740 3610);
PAINT MONO (-1740 3610);
DISPLAY INVISIBLE (-1740 3610);
FORCEPROP 1 LASTPIN (-1750 3600) BN 39
J 2
(-1700 3610);
DISPLAY 0.617021 (-1700 3610);
PAINT PINK (-1700 3610);
FORCEPROP 2 LAST CDS_LIB mstr_standard
J 2
(-1700 3600);
DISPLAY 0.787234 (-1700 3600);
PAINT MONO (-1700 3600);
DISPLAY INVISIBLE (-1700 3600);
FORCEPROP 1 LAST BODY_TYPE PLUMBING
J 2
(-1700 3550);
DISPLAY 1.234043 (-1700 3550);
PAINT GREEN (-1700 3550);
DISPLAY INVISIBLE (-1700 3550);
FORCEPROP 1 LAST HDL_TAP TRUE
J 2
(-2025 3475);
DISPLAY 1.234043 (-2025 3475);
PAINT GREEN (-2025 3475);
DISPLAY INVISIBLE (-2025 3475);
FORCEPROP 1 LAST PATH I76
J 2
(-1700 3600);
DISPLAY 0.936170 (-1700 3600);
PAINT GREEN (-1700 3600);
DISPLAY INVISIBLE (-1700 3600);
FORCEADD TAP..6
R 2
(-1700 3200);
FORCEPROP 3 LASTPIN (-1750 3200) SIG_NAME M_K_DQ<31>
J 0
(-1740 3210);
DISPLAY 0.659574 (-1740 3210);
PAINT MONO (-1740 3210);
DISPLAY INVISIBLE (-1740 3210);
FORCEPROP 1 LASTPIN (-1750 3200) BN 31
J 2
(-1700 3210);
DISPLAY 0.617021 (-1700 3210);
PAINT PINK (-1700 3210);
FORCEPROP 2 LAST CDS_LIB mstr_standard
J 2
(-1700 3200);
DISPLAY 0.787234 (-1700 3200);
PAINT MONO (-1700 3200);
DISPLAY INVISIBLE (-1700 3200);
FORCEPROP 1 LAST BODY_TYPE PLUMBING
J 2
(-1700 3150);
DISPLAY 1.234043 (-1700 3150);
PAINT GREEN (-1700 3150);
DISPLAY INVISIBLE (-1700 3150);
FORCEPROP 1 LAST HDL_TAP TRUE
J 2
(-2025 3075);
DISPLAY 1.234043 (-2025 3075);
PAINT GREEN (-2025 3075);
DISPLAY INVISIBLE (-2025 3075);
FORCEPROP 1 LAST PATH I77
J 2
(-1700 3200);
DISPLAY 0.936170 (-1700 3200);
PAINT GREEN (-1700 3200);
DISPLAY INVISIBLE (-1700 3200);
FORCEADD TAP..6
R 2
(-1700 3250);
FORCEPROP 3 LASTPIN (-1750 3250) SIG_NAME M_K_DQ<30>
J 0
(-1740 3260);
DISPLAY 0.659574 (-1740 3260);
PAINT MONO (-1740 3260);
DISPLAY INVISIBLE (-1740 3260);
FORCEPROP 1 LASTPIN (-1750 3250) BN 30
J 2
(-1700 3260);
DISPLAY 0.617021 (-1700 3260);
PAINT PINK (-1700 3260);
FORCEPROP 2 LAST CDS_LIB mstr_standard
J 2
(-1700 3250);
DISPLAY 0.787234 (-1700 3250);
PAINT MONO (-1700 3250);
DISPLAY INVISIBLE (-1700 3250);
FORCEPROP 1 LAST BODY_TYPE PLUMBING
J 2
(-1700 3200);
DISPLAY 1.234043 (-1700 3200);
PAINT GREEN (-1700 3200);
DISPLAY INVISIBLE (-1700 3200);
FORCEPROP 1 LAST HDL_TAP TRUE
J 2
(-2025 3125);
DISPLAY 1.234043 (-2025 3125);
PAINT GREEN (-2025 3125);
DISPLAY INVISIBLE (-2025 3125);
FORCEPROP 1 LAST PATH I78
J 2
(-1700 3250);
DISPLAY 0.936170 (-1700 3250);
PAINT GREEN (-1700 3250);
DISPLAY INVISIBLE (-1700 3250);
FORCEADD TAP..6
R 2
(-1700 3150);
FORCEPROP 3 LASTPIN (-1750 3150) SIG_NAME M_K_DQ<28>
J 0
(-1740 3160);
DISPLAY 0.659574 (-1740 3160);
PAINT MONO (-1740 3160);
DISPLAY INVISIBLE (-1740 3160);
FORCEPROP 1 LASTPIN (-1750 3150) BN 28
J 2
(-1700 3160);
DISPLAY 0.617021 (-1700 3160);
PAINT PINK (-1700 3160);
FORCEPROP 2 LAST CDS_LIB mstr_standard
J 2
(-1700 3150);
DISPLAY 0.787234 (-1700 3150);
PAINT MONO (-1700 3150);
DISPLAY INVISIBLE (-1700 3150);
FORCEPROP 1 LAST BODY_TYPE PLUMBING
J 2
(-1700 3100);
DISPLAY 1.234043 (-1700 3100);
PAINT GREEN (-1700 3100);
DISPLAY INVISIBLE (-1700 3100);
FORCEPROP 1 LAST HDL_TAP TRUE
J 2
(-2025 3025);
DISPLAY 1.234043 (-2025 3025);
PAINT GREEN (-2025 3025);
DISPLAY INVISIBLE (-2025 3025);
FORCEPROP 1 LAST PATH I79
J 2
(-1700 3150);
DISPLAY 0.936170 (-1700 3150);
PAINT GREEN (-1700 3150);
DISPLAY INVISIBLE (-1700 3150);
FORCEADD TAP..6
R 2
(900 4750);
FORCEPROP 3 LASTPIN (850 4750) SIG_NAME M_K_DQS_DN<13>
J 0
(860 4760);
DISPLAY 0.659574 (860 4760);
PAINT MONO (860 4760);
DISPLAY INVISIBLE (860 4760);
FORCEPROP 1 LASTPIN (850 4750) BN 13
J 2
(900 4760);
DISPLAY 0.617021 (900 4760);
PAINT PINK (900 4760);
FORCEPROP 2 LAST CDS_LIB mstr_standard
J 0
(900 4750);
DISPLAY 0.787234 (900 4750);
PAINT MONO (900 4750);
DISPLAY INVISIBLE (900 4750);
FORCEPROP 1 LAST BODY_TYPE PLUMBING
J 2
(900 4700);
DISPLAY 1.234043 (900 4700);
PAINT GREEN (900 4700);
DISPLAY INVISIBLE (900 4700);
FORCEPROP 1 LAST HDL_TAP TRUE
J 2
(575 4625);
DISPLAY 1.234043 (575 4625);
PAINT GREEN (575 4625);
DISPLAY INVISIBLE (575 4625);
FORCEPROP 1 LAST PATH I8
J 2
(900 4750);
DISPLAY 0.936170 (900 4750);
PAINT GREEN (900 4750);
DISPLAY INVISIBLE (900 4750);
FORCEADD TAP..6
R 2
(-1700 3300);
FORCEPROP 3 LASTPIN (-1750 3300) SIG_NAME M_K_DQ<33>
J 0
(-1740 3310);
DISPLAY 0.659574 (-1740 3310);
PAINT MONO (-1740 3310);
DISPLAY INVISIBLE (-1740 3310);
FORCEPROP 1 LASTPIN (-1750 3300) BN 33
J 2
(-1700 3310);
DISPLAY 0.617021 (-1700 3310);
PAINT PINK (-1700 3310);
FORCEPROP 2 LAST CDS_LIB mstr_standard
J 2
(-1700 3300);
DISPLAY 0.787234 (-1700 3300);
PAINT MONO (-1700 3300);
DISPLAY INVISIBLE (-1700 3300);
FORCEPROP 1 LAST BODY_TYPE PLUMBING
J 2
(-1700 3250);
DISPLAY 1.234043 (-1700 3250);
PAINT GREEN (-1700 3250);
DISPLAY INVISIBLE (-1700 3250);
FORCEPROP 1 LAST HDL_TAP TRUE
J 2
(-2025 3175);
DISPLAY 1.234043 (-2025 3175);
PAINT GREEN (-2025 3175);
DISPLAY INVISIBLE (-2025 3175);
FORCEPROP 1 LAST PATH I80
J 2
(-1700 3300);
DISPLAY 0.936170 (-1700 3300);
PAINT GREEN (-1700 3300);
DISPLAY INVISIBLE (-1700 3300);
FORCEADD TAP..6
R 2
(-1700 3350);
FORCEPROP 3 LASTPIN (-1750 3350) SIG_NAME M_K_DQ<32>
J 0
(-1740 3360);
DISPLAY 0.659574 (-1740 3360);
PAINT MONO (-1740 3360);
DISPLAY INVISIBLE (-1740 3360);
FORCEPROP 1 LASTPIN (-1750 3350) BN 32
J 2
(-1700 3360);
DISPLAY 0.617021 (-1700 3360);
PAINT PINK (-1700 3360);
FORCEPROP 2 LAST CDS_LIB mstr_standard
J 2
(-1700 3350);
DISPLAY 0.787234 (-1700 3350);
PAINT MONO (-1700 3350);
DISPLAY INVISIBLE (-1700 3350);
FORCEPROP 1 LAST BODY_TYPE PLUMBING
J 2
(-1700 3300);
DISPLAY 1.234043 (-1700 3300);
PAINT GREEN (-1700 3300);
DISPLAY INVISIBLE (-1700 3300);
FORCEPROP 1 LAST HDL_TAP TRUE
J 2
(-2025 3225);
DISPLAY 1.234043 (-2025 3225);
PAINT GREEN (-2025 3225);
DISPLAY INVISIBLE (-2025 3225);
FORCEPROP 1 LAST PATH I81
J 2
(-1700 3350);
DISPLAY 0.936170 (-1700 3350);
PAINT GREEN (-1700 3350);
DISPLAY INVISIBLE (-1700 3350);
FORCEADD TAP..6
R 2
(-1700 2950);
FORCEPROP 3 LASTPIN (-1750 2950) SIG_NAME M_K_DQ<24>
J 0
(-1740 2960);
DISPLAY 0.659574 (-1740 2960);
PAINT MONO (-1740 2960);
DISPLAY INVISIBLE (-1740 2960);
FORCEPROP 1 LASTPIN (-1750 2950) BN 24
J 2
(-1700 2960);
DISPLAY 0.617021 (-1700 2960);
PAINT PINK (-1700 2960);
FORCEPROP 2 LAST CDS_LIB mstr_standard
J 2
(-1700 2950);
DISPLAY 0.787234 (-1700 2950);
PAINT MONO (-1700 2950);
DISPLAY INVISIBLE (-1700 2950);
FORCEPROP 1 LAST BODY_TYPE PLUMBING
J 2
(-1700 2900);
DISPLAY 1.234043 (-1700 2900);
PAINT GREEN (-1700 2900);
DISPLAY INVISIBLE (-1700 2900);
FORCEPROP 1 LAST HDL_TAP TRUE
J 2
(-2025 2825);
DISPLAY 1.234043 (-2025 2825);
PAINT GREEN (-2025 2825);
DISPLAY INVISIBLE (-2025 2825);
FORCEPROP 1 LAST PATH I82
J 2
(-1700 2950);
DISPLAY 0.936170 (-1700 2950);
PAINT GREEN (-1700 2950);
DISPLAY INVISIBLE (-1700 2950);
FORCEADD TAP..6
R 2
(-1700 2900);
FORCEPROP 3 LASTPIN (-1750 2900) SIG_NAME M_K_DQ<25>
J 0
(-1740 2910);
DISPLAY 0.659574 (-1740 2910);
PAINT MONO (-1740 2910);
DISPLAY INVISIBLE (-1740 2910);
FORCEPROP 1 LASTPIN (-1750 2900) BN 25
J 2
(-1700 2910);
DISPLAY 0.617021 (-1700 2910);
PAINT PINK (-1700 2910);
FORCEPROP 2 LAST CDS_LIB mstr_standard
J 2
(-1700 2900);
DISPLAY 0.787234 (-1700 2900);
PAINT MONO (-1700 2900);
DISPLAY INVISIBLE (-1700 2900);
FORCEPROP 1 LAST BODY_TYPE PLUMBING
J 2
(-1700 2850);
DISPLAY 1.234043 (-1700 2850);
PAINT GREEN (-1700 2850);
DISPLAY INVISIBLE (-1700 2850);
FORCEPROP 1 LAST HDL_TAP TRUE
J 2
(-2025 2775);
DISPLAY 1.234043 (-2025 2775);
PAINT GREEN (-2025 2775);
DISPLAY INVISIBLE (-2025 2775);
FORCEPROP 1 LAST PATH I83
J 2
(-1700 2900);
DISPLAY 0.936170 (-1700 2900);
PAINT GREEN (-1700 2900);
DISPLAY INVISIBLE (-1700 2900);
FORCEADD TAP..6
R 2
(-1700 3000);
FORCEPROP 3 LASTPIN (-1750 3000) SIG_NAME M_K_DQ<27>
J 0
(-1740 3010);
DISPLAY 0.659574 (-1740 3010);
PAINT MONO (-1740 3010);
DISPLAY INVISIBLE (-1740 3010);
FORCEPROP 1 LASTPIN (-1750 3000) BN 27
J 2
(-1700 3010);
DISPLAY 0.617021 (-1700 3010);
PAINT PINK (-1700 3010);
FORCEPROP 2 LAST CDS_LIB mstr_standard
J 2
(-1700 3000);
DISPLAY 0.787234 (-1700 3000);
PAINT MONO (-1700 3000);
DISPLAY INVISIBLE (-1700 3000);
FORCEPROP 1 LAST BODY_TYPE PLUMBING
J 2
(-1700 2950);
DISPLAY 1.234043 (-1700 2950);
PAINT GREEN (-1700 2950);
DISPLAY INVISIBLE (-1700 2950);
FORCEPROP 1 LAST HDL_TAP TRUE
J 2
(-2025 2875);
DISPLAY 1.234043 (-2025 2875);
PAINT GREEN (-2025 2875);
DISPLAY INVISIBLE (-2025 2875);
FORCEPROP 1 LAST PATH I84
J 2
(-1700 3000);
DISPLAY 0.936170 (-1700 3000);
PAINT GREEN (-1700 3000);
DISPLAY INVISIBLE (-1700 3000);
FORCEADD TAP..6
R 2
(-1700 3100);
FORCEPROP 3 LASTPIN (-1750 3100) SIG_NAME M_K_DQ<29>
J 0
(-1740 3110);
DISPLAY 0.659574 (-1740 3110);
PAINT MONO (-1740 3110);
DISPLAY INVISIBLE (-1740 3110);
FORCEPROP 1 LASTPIN (-1750 3100) BN 29
J 2
(-1700 3110);
DISPLAY 0.617021 (-1700 3110);
PAINT PINK (-1700 3110);
FORCEPROP 2 LAST CDS_LIB mstr_standard
J 2
(-1700 3100);
DISPLAY 0.787234 (-1700 3100);
PAINT MONO (-1700 3100);
DISPLAY INVISIBLE (-1700 3100);
FORCEPROP 1 LAST BODY_TYPE PLUMBING
J 2
(-1700 3050);
DISPLAY 1.234043 (-1700 3050);
PAINT GREEN (-1700 3050);
DISPLAY INVISIBLE (-1700 3050);
FORCEPROP 1 LAST HDL_TAP TRUE
J 2
(-2025 2975);
DISPLAY 1.234043 (-2025 2975);
PAINT GREEN (-2025 2975);
DISPLAY INVISIBLE (-2025 2975);
FORCEPROP 1 LAST PATH I85
J 2
(-1700 3100);
DISPLAY 0.936170 (-1700 3100);
PAINT GREEN (-1700 3100);
DISPLAY INVISIBLE (-1700 3100);
FORCEADD TAP..6
R 2
(-1700 3050);
FORCEPROP 3 LASTPIN (-1750 3050) SIG_NAME M_K_DQ<26>
J 0
(-1740 3060);
DISPLAY 0.659574 (-1740 3060);
PAINT MONO (-1740 3060);
DISPLAY INVISIBLE (-1740 3060);
FORCEPROP 1 LASTPIN (-1750 3050) BN 26
J 2
(-1700 3060);
DISPLAY 0.617021 (-1700 3060);
PAINT PINK (-1700 3060);
FORCEPROP 2 LAST CDS_LIB mstr_standard
J 2
(-1700 3050);
DISPLAY 0.787234 (-1700 3050);
PAINT MONO (-1700 3050);
DISPLAY INVISIBLE (-1700 3050);
FORCEPROP 1 LAST BODY_TYPE PLUMBING
J 2
(-1700 3000);
DISPLAY 1.234043 (-1700 3000);
PAINT GREEN (-1700 3000);
DISPLAY INVISIBLE (-1700 3000);
FORCEPROP 1 LAST HDL_TAP TRUE
J 2
(-2025 2925);
DISPLAY 1.234043 (-2025 2925);
PAINT GREEN (-2025 2925);
DISPLAY INVISIBLE (-2025 2925);
FORCEPROP 1 LAST PATH I86
J 2
(-1700 3050);
DISPLAY 0.936170 (-1700 3050);
PAINT GREEN (-1700 3050);
DISPLAY INVISIBLE (-1700 3050);
FORCEADD TAP..6
R 2
(-1700 2650);
FORCEPROP 3 LASTPIN (-1750 2650) SIG_NAME M_K_DQ<18>
J 0
(-1740 2660);
DISPLAY 0.659574 (-1740 2660);
PAINT MONO (-1740 2660);
DISPLAY INVISIBLE (-1740 2660);
FORCEPROP 1 LASTPIN (-1750 2650) BN 18
J 2
(-1700 2660);
DISPLAY 0.617021 (-1700 2660);
PAINT PINK (-1700 2660);
FORCEPROP 2 LAST CDS_LIB mstr_standard
J 2
(-1700 2650);
DISPLAY 0.787234 (-1700 2650);
PAINT MONO (-1700 2650);
DISPLAY INVISIBLE (-1700 2650);
FORCEPROP 1 LAST BODY_TYPE PLUMBING
J 2
(-1700 2600);
DISPLAY 1.234043 (-1700 2600);
PAINT GREEN (-1700 2600);
DISPLAY INVISIBLE (-1700 2600);
FORCEPROP 1 LAST HDL_TAP TRUE
J 2
(-2025 2525);
DISPLAY 1.234043 (-2025 2525);
PAINT GREEN (-2025 2525);
DISPLAY INVISIBLE (-2025 2525);
FORCEPROP 1 LAST PATH I87
J 2
(-1700 2650);
DISPLAY 0.936170 (-1700 2650);
PAINT GREEN (-1700 2650);
DISPLAY INVISIBLE (-1700 2650);
FORCEADD TAP..6
R 2
(-1700 2700);
FORCEPROP 3 LASTPIN (-1750 2700) SIG_NAME M_K_DQ<21>
J 0
(-1740 2710);
DISPLAY 0.659574 (-1740 2710);
PAINT MONO (-1740 2710);
DISPLAY INVISIBLE (-1740 2710);
FORCEPROP 1 LASTPIN (-1750 2700) BN 21
J 2
(-1700 2710);
DISPLAY 0.617021 (-1700 2710);
PAINT PINK (-1700 2710);
FORCEPROP 2 LAST CDS_LIB mstr_standard
J 2
(-1700 2700);
DISPLAY 0.787234 (-1700 2700);
PAINT MONO (-1700 2700);
DISPLAY INVISIBLE (-1700 2700);
FORCEPROP 1 LAST BODY_TYPE PLUMBING
J 2
(-1700 2650);
DISPLAY 1.234043 (-1700 2650);
PAINT GREEN (-1700 2650);
DISPLAY INVISIBLE (-1700 2650);
FORCEPROP 1 LAST HDL_TAP TRUE
J 2
(-2025 2575);
DISPLAY 1.234043 (-2025 2575);
PAINT GREEN (-2025 2575);
DISPLAY INVISIBLE (-2025 2575);
FORCEPROP 1 LAST PATH I88
J 2
(-1700 2700);
DISPLAY 0.936170 (-1700 2700);
PAINT GREEN (-1700 2700);
DISPLAY INVISIBLE (-1700 2700);
FORCEADD TAP..6
R 2
(-1700 2750);
FORCEPROP 3 LASTPIN (-1750 2750) SIG_NAME M_K_DQ<20>
J 0
(-1740 2760);
DISPLAY 0.659574 (-1740 2760);
PAINT MONO (-1740 2760);
DISPLAY INVISIBLE (-1740 2760);
FORCEPROP 1 LASTPIN (-1750 2750) BN 20
J 2
(-1700 2760);
DISPLAY 0.617021 (-1700 2760);
PAINT PINK (-1700 2760);
FORCEPROP 2 LAST CDS_LIB mstr_standard
J 2
(-1700 2750);
DISPLAY 0.787234 (-1700 2750);
PAINT MONO (-1700 2750);
DISPLAY INVISIBLE (-1700 2750);
FORCEPROP 1 LAST BODY_TYPE PLUMBING
J 2
(-1700 2700);
DISPLAY 1.234043 (-1700 2700);
PAINT GREEN (-1700 2700);
DISPLAY INVISIBLE (-1700 2700);
FORCEPROP 1 LAST HDL_TAP TRUE
J 2
(-2025 2625);
DISPLAY 1.234043 (-2025 2625);
PAINT GREEN (-2025 2625);
DISPLAY INVISIBLE (-2025 2625);
FORCEPROP 1 LAST PATH I89
J 2
(-1700 2750);
DISPLAY 0.936170 (-1700 2750);
PAINT GREEN (-1700 2750);
DISPLAY INVISIBLE (-1700 2750);
FORCEADD TAP..6
R 2
(900 4650);
FORCEPROP 3 LASTPIN (850 4650) SIG_NAME M_K_DQS_DN<12>
J 0
(860 4660);
DISPLAY 0.659574 (860 4660);
PAINT MONO (860 4660);
DISPLAY INVISIBLE (860 4660);
FORCEPROP 1 LASTPIN (850 4650) BN 12
J 2
(900 4660);
DISPLAY 0.617021 (900 4660);
PAINT PINK (900 4660);
FORCEPROP 2 LAST CDS_LIB mstr_standard
J 0
(900 4650);
DISPLAY 0.787234 (900 4650);
PAINT MONO (900 4650);
DISPLAY INVISIBLE (900 4650);
FORCEPROP 1 LAST BODY_TYPE PLUMBING
J 2
(900 4600);
DISPLAY 1.234043 (900 4600);
PAINT GREEN (900 4600);
DISPLAY INVISIBLE (900 4600);
FORCEPROP 1 LAST HDL_TAP TRUE
J 2
(575 4525);
DISPLAY 1.234043 (575 4525);
PAINT GREEN (575 4525);
DISPLAY INVISIBLE (575 4525);
FORCEPROP 1 LAST PATH I9
J 2
(900 4650);
DISPLAY 0.936170 (900 4650);
PAINT GREEN (900 4650);
DISPLAY INVISIBLE (900 4650);
FORCEADD TAP..6
R 2
(-1700 2850);
FORCEPROP 3 LASTPIN (-1750 2850) SIG_NAME M_K_DQ<22>
J 0
(-1740 2860);
DISPLAY 0.659574 (-1740 2860);
PAINT MONO (-1740 2860);
DISPLAY INVISIBLE (-1740 2860);
FORCEPROP 1 LASTPIN (-1750 2850) BN 22
J 2
(-1700 2860);
DISPLAY 0.617021 (-1700 2860);
PAINT PINK (-1700 2860);
FORCEPROP 2 LAST CDS_LIB mstr_standard
J 2
(-1700 2850);
DISPLAY 0.787234 (-1700 2850);
PAINT MONO (-1700 2850);
DISPLAY INVISIBLE (-1700 2850);
FORCEPROP 1 LAST BODY_TYPE PLUMBING
J 2
(-1700 2800);
DISPLAY 1.234043 (-1700 2800);
PAINT GREEN (-1700 2800);
DISPLAY INVISIBLE (-1700 2800);
FORCEPROP 1 LAST HDL_TAP TRUE
J 2
(-2025 2725);
DISPLAY 1.234043 (-2025 2725);
PAINT GREEN (-2025 2725);
DISPLAY INVISIBLE (-2025 2725);
FORCEPROP 1 LAST PATH I90
J 2
(-1700 2850);
DISPLAY 0.936170 (-1700 2850);
PAINT GREEN (-1700 2850);
DISPLAY INVISIBLE (-1700 2850);
FORCEADD TAP..6
R 2
(-1700 2800);
FORCEPROP 3 LASTPIN (-1750 2800) SIG_NAME M_K_DQ<23>
J 0
(-1740 2810);
DISPLAY 0.659574 (-1740 2810);
PAINT MONO (-1740 2810);
DISPLAY INVISIBLE (-1740 2810);
FORCEPROP 1 LASTPIN (-1750 2800) BN 23
J 2
(-1700 2810);
DISPLAY 0.617021 (-1700 2810);
PAINT PINK (-1700 2810);
FORCEPROP 2 LAST CDS_LIB mstr_standard
J 2
(-1700 2800);
DISPLAY 0.787234 (-1700 2800);
PAINT MONO (-1700 2800);
DISPLAY INVISIBLE (-1700 2800);
FORCEPROP 1 LAST BODY_TYPE PLUMBING
J 2
(-1700 2750);
DISPLAY 1.234043 (-1700 2750);
PAINT GREEN (-1700 2750);
DISPLAY INVISIBLE (-1700 2750);
FORCEPROP 1 LAST HDL_TAP TRUE
J 2
(-2025 2675);
DISPLAY 1.234043 (-2025 2675);
PAINT GREEN (-2025 2675);
DISPLAY INVISIBLE (-2025 2675);
FORCEPROP 1 LAST PATH I91
J 2
(-1700 2800);
DISPLAY 0.936170 (-1700 2800);
PAINT GREEN (-1700 2800);
DISPLAY INVISIBLE (-1700 2800);
FORCEADD TAP..6
R 2
(-1700 2400);
FORCEPROP 3 LASTPIN (-1750 2400) SIG_NAME M_K_DQ<15>
J 0
(-1740 2410);
DISPLAY 0.659574 (-1740 2410);
PAINT MONO (-1740 2410);
DISPLAY INVISIBLE (-1740 2410);
FORCEPROP 1 LASTPIN (-1750 2400) BN 15
J 2
(-1700 2410);
DISPLAY 0.617021 (-1700 2410);
PAINT PINK (-1700 2410);
FORCEPROP 2 LAST CDS_LIB mstr_standard
J 2
(-1700 2400);
DISPLAY 0.787234 (-1700 2400);
PAINT MONO (-1700 2400);
DISPLAY INVISIBLE (-1700 2400);
FORCEPROP 1 LAST BODY_TYPE PLUMBING
J 2
(-1700 2350);
DISPLAY 1.234043 (-1700 2350);
PAINT GREEN (-1700 2350);
DISPLAY INVISIBLE (-1700 2350);
FORCEPROP 1 LAST HDL_TAP TRUE
J 2
(-2025 2275);
DISPLAY 1.234043 (-2025 2275);
PAINT GREEN (-2025 2275);
DISPLAY INVISIBLE (-2025 2275);
FORCEPROP 1 LAST PATH I92
J 2
(-1700 2400);
DISPLAY 0.936170 (-1700 2400);
PAINT GREEN (-1700 2400);
DISPLAY INVISIBLE (-1700 2400);
FORCEADD TAP..6
R 2
(-1700 2450);
FORCEPROP 3 LASTPIN (-1750 2450) SIG_NAME M_K_DQ<14>
J 0
(-1740 2460);
DISPLAY 0.659574 (-1740 2460);
PAINT MONO (-1740 2460);
DISPLAY INVISIBLE (-1740 2460);
FORCEPROP 1 LASTPIN (-1750 2450) BN 14
J 2
(-1700 2460);
DISPLAY 0.617021 (-1700 2460);
PAINT PINK (-1700 2460);
FORCEPROP 2 LAST CDS_LIB mstr_standard
J 2
(-1700 2450);
DISPLAY 0.787234 (-1700 2450);
PAINT MONO (-1700 2450);
DISPLAY INVISIBLE (-1700 2450);
FORCEPROP 1 LAST BODY_TYPE PLUMBING
J 2
(-1700 2400);
DISPLAY 1.234043 (-1700 2400);
PAINT GREEN (-1700 2400);
DISPLAY INVISIBLE (-1700 2400);
FORCEPROP 1 LAST HDL_TAP TRUE
J 2
(-2025 2325);
DISPLAY 1.234043 (-2025 2325);
PAINT GREEN (-2025 2325);
DISPLAY INVISIBLE (-2025 2325);
FORCEPROP 1 LAST PATH I93
J 2
(-1700 2450);
DISPLAY 0.936170 (-1700 2450);
PAINT GREEN (-1700 2450);
DISPLAY INVISIBLE (-1700 2450);
FORCEADD TAP..6
R 2
(-1700 2550);
FORCEPROP 3 LASTPIN (-1750 2550) SIG_NAME M_K_DQ<16>
J 0
(-1740 2560);
DISPLAY 0.659574 (-1740 2560);
PAINT MONO (-1740 2560);
DISPLAY INVISIBLE (-1740 2560);
FORCEPROP 1 LASTPIN (-1750 2550) BN 16
J 2
(-1700 2560);
DISPLAY 0.617021 (-1700 2560);
PAINT PINK (-1700 2560);
FORCEPROP 2 LAST CDS_LIB mstr_standard
J 2
(-1700 2550);
DISPLAY 0.787234 (-1700 2550);
PAINT MONO (-1700 2550);
DISPLAY INVISIBLE (-1700 2550);
FORCEPROP 1 LAST BODY_TYPE PLUMBING
J 2
(-1700 2500);
DISPLAY 1.234043 (-1700 2500);
PAINT GREEN (-1700 2500);
DISPLAY INVISIBLE (-1700 2500);
FORCEPROP 1 LAST HDL_TAP TRUE
J 2
(-2025 2425);
DISPLAY 1.234043 (-2025 2425);
PAINT GREEN (-2025 2425);
DISPLAY INVISIBLE (-2025 2425);
FORCEPROP 1 LAST PATH I94
J 2
(-1700 2550);
DISPLAY 0.936170 (-1700 2550);
PAINT GREEN (-1700 2550);
DISPLAY INVISIBLE (-1700 2550);
FORCEADD TAP..6
R 2
(-1700 2500);
FORCEPROP 3 LASTPIN (-1750 2500) SIG_NAME M_K_DQ<17>
J 0
(-1740 2510);
DISPLAY 0.659574 (-1740 2510);
PAINT MONO (-1740 2510);
DISPLAY INVISIBLE (-1740 2510);
FORCEPROP 1 LASTPIN (-1750 2500) BN 17
J 2
(-1700 2510);
DISPLAY 0.617021 (-1700 2510);
PAINT PINK (-1700 2510);
FORCEPROP 2 LAST CDS_LIB mstr_standard
J 2
(-1700 2500);
DISPLAY 0.787234 (-1700 2500);
PAINT MONO (-1700 2500);
DISPLAY INVISIBLE (-1700 2500);
FORCEPROP 1 LAST BODY_TYPE PLUMBING
J 2
(-1700 2450);
DISPLAY 1.234043 (-1700 2450);
PAINT GREEN (-1700 2450);
DISPLAY INVISIBLE (-1700 2450);
FORCEPROP 1 LAST HDL_TAP TRUE
J 2
(-2025 2375);
DISPLAY 1.234043 (-2025 2375);
PAINT GREEN (-2025 2375);
DISPLAY INVISIBLE (-2025 2375);
FORCEPROP 1 LAST PATH I95
J 2
(-1700 2500);
DISPLAY 0.936170 (-1700 2500);
PAINT GREEN (-1700 2500);
DISPLAY INVISIBLE (-1700 2500);
FORCEADD TAP..6
R 2
(-1700 2600);
FORCEPROP 3 LASTPIN (-1750 2600) SIG_NAME M_K_DQ<19>
J 0
(-1740 2610);
DISPLAY 0.659574 (-1740 2610);
PAINT MONO (-1740 2610);
DISPLAY INVISIBLE (-1740 2610);
FORCEPROP 1 LASTPIN (-1750 2600) BN 19
J 2
(-1700 2610);
DISPLAY 0.617021 (-1700 2610);
PAINT PINK (-1700 2610);
FORCEPROP 2 LAST CDS_LIB mstr_standard
J 2
(-1700 2600);
DISPLAY 0.787234 (-1700 2600);
PAINT MONO (-1700 2600);
DISPLAY INVISIBLE (-1700 2600);
FORCEPROP 1 LAST BODY_TYPE PLUMBING
J 2
(-1700 2550);
DISPLAY 1.234043 (-1700 2550);
PAINT GREEN (-1700 2550);
DISPLAY INVISIBLE (-1700 2550);
FORCEPROP 1 LAST HDL_TAP TRUE
J 2
(-2025 2475);
DISPLAY 1.234043 (-2025 2475);
PAINT GREEN (-2025 2475);
DISPLAY INVISIBLE (-2025 2475);
FORCEPROP 1 LAST PATH I96
J 2
(-1700 2600);
DISPLAY 0.936170 (-1700 2600);
PAINT GREEN (-1700 2600);
DISPLAY INVISIBLE (-1700 2600);
FORCEADD TAP..6
R 2
(-1700 2350);
FORCEPROP 3 LASTPIN (-1750 2350) SIG_NAME M_K_DQ<12>
J 0
(-1740 2360);
DISPLAY 0.659574 (-1740 2360);
PAINT MONO (-1740 2360);
DISPLAY INVISIBLE (-1740 2360);
FORCEPROP 1 LASTPIN (-1750 2350) BN 12
J 2
(-1700 2360);
DISPLAY 0.617021 (-1700 2360);
PAINT PINK (-1700 2360);
FORCEPROP 2 LAST CDS_LIB mstr_standard
J 2
(-1700 2350);
DISPLAY 0.787234 (-1700 2350);
PAINT MONO (-1700 2350);
DISPLAY INVISIBLE (-1700 2350);
FORCEPROP 1 LAST BODY_TYPE PLUMBING
J 2
(-1700 2300);
DISPLAY 1.234043 (-1700 2300);
PAINT GREEN (-1700 2300);
DISPLAY INVISIBLE (-1700 2300);
FORCEPROP 1 LAST HDL_TAP TRUE
J 2
(-2025 2225);
DISPLAY 1.234043 (-2025 2225);
PAINT GREEN (-2025 2225);
DISPLAY INVISIBLE (-2025 2225);
FORCEPROP 1 LAST PATH I97
J 2
(-1700 2350);
DISPLAY 0.936170 (-1700 2350);
PAINT GREEN (-1700 2350);
DISPLAY INVISIBLE (-1700 2350);
FORCEADD TAP..6
R 2
(-1700 2250);
FORCEPROP 3 LASTPIN (-1750 2250) SIG_NAME M_K_DQ<10>
J 0
(-1740 2260);
DISPLAY 0.659574 (-1740 2260);
PAINT MONO (-1740 2260);
DISPLAY INVISIBLE (-1740 2260);
FORCEPROP 1 LASTPIN (-1750 2250) BN 10
J 2
(-1700 2260);
DISPLAY 0.617021 (-1700 2260);
PAINT PINK (-1700 2260);
FORCEPROP 2 LAST CDS_LIB mstr_standard
J 2
(-1700 2250);
DISPLAY 0.787234 (-1700 2250);
PAINT MONO (-1700 2250);
DISPLAY INVISIBLE (-1700 2250);
FORCEPROP 1 LAST BODY_TYPE PLUMBING
J 2
(-1700 2200);
DISPLAY 1.234043 (-1700 2200);
PAINT GREEN (-1700 2200);
DISPLAY INVISIBLE (-1700 2200);
FORCEPROP 1 LAST HDL_TAP TRUE
J 2
(-2025 2125);
DISPLAY 1.234043 (-2025 2125);
PAINT GREEN (-2025 2125);
DISPLAY INVISIBLE (-2025 2125);
FORCEPROP 1 LAST PATH I98
J 2
(-1700 2250);
DISPLAY 0.936170 (-1700 2250);
PAINT GREEN (-1700 2250);
DISPLAY INVISIBLE (-1700 2250);
FORCEADD TAP..6
R 2
(-1700 2300);
FORCEPROP 3 LASTPIN (-1750 2300) SIG_NAME M_K_DQ<13>
J 0
(-1740 2310);
DISPLAY 0.659574 (-1740 2310);
PAINT MONO (-1740 2310);
DISPLAY INVISIBLE (-1740 2310);
FORCEPROP 1 LASTPIN (-1750 2300) BN 13
J 2
(-1700 2310);
DISPLAY 0.617021 (-1700 2310);
PAINT PINK (-1700 2310);
FORCEPROP 2 LAST CDS_LIB mstr_standard
J 2
(-1700 2300);
DISPLAY 0.787234 (-1700 2300);
PAINT MONO (-1700 2300);
DISPLAY INVISIBLE (-1700 2300);
FORCEPROP 1 LAST BODY_TYPE PLUMBING
J 2
(-1700 2250);
DISPLAY 1.234043 (-1700 2250);
PAINT GREEN (-1700 2250);
DISPLAY INVISIBLE (-1700 2250);
FORCEPROP 1 LAST HDL_TAP TRUE
J 2
(-2025 2175);
DISPLAY 1.234043 (-2025 2175);
PAINT GREEN (-2025 2175);
DISPLAY INVISIBLE (-2025 2175);
FORCEPROP 1 LAST PATH I99
J 2
(-1700 2300);
DISPLAY 0.936170 (-1700 2300);
PAINT GREEN (-1700 2300);
DISPLAY INVISIBLE (-1700 2300);
FORCEADD BOM_NOTE..1
(-5000 5275);
FORCEPROP 0 LAST L1 STUFF FOR SKU A & B
J 0
(-5150 5175);
DISPLAY 1.063830 (-5150 5175);
PAINT WHITE (-5150 5175);
FORCEPROP 2 LAST CDS_LIB mstr_symbols
J 0
(-5000 5275);
PAINT ORANGE (-5000 5275);
DISPLAY INVISIBLE (-5000 5275);
FORCEPROP 2 LAST BOM_COST SB
J 0
(-5150 5250);
DISPLAY 1.361702 (-5150 5250);
PAINT ORANGE (-5150 5250);
DISPLAY INVISIBLE (-5150 5250);
FORCEPROP 1 LAST COMMENT_BODY TRUE
J 0
(-4975 5375);
DISPLAY 1.319149 (-4975 5375);
PAINT ORANGE (-4975 5375);
DISPLAY INVISIBLE (-4975 5375);
FORCEPROP 2 LAST ROOM SB_HEADERS
J 0
(-5150 5250);
DISPLAY 1.361702 (-5150 5250);
PAINT ORANGE (-5150 5250);
DISPLAY INVISIBLE (-5150 5250);
FORCEADD INTEL_CORP_BPAGE..1
(2650 500);
FORCEPROP 1 LAST CDS_CON_LAST_MODIFIED Tue Dec 01 11:51:44 2015
J 0
(1225 825);
DISPLAY 0.787234 (1225 825);
PAINT ORANGE (1225 825);
DISPLAY INVISIBLE (1225 825);
FORCEPROP 1 LAST CUSTOM_TXT_CDS <CURRENT_DESIGN_SHEET> OF <TOTAL_DESIGN_SHEETS>
J 0
(2150 525);
PAINT GREEN (2150 525);
FORCEPROP 1 LAST CUSTOM_TXT_CDS <CON_LAST_MODIFIED>
J 0
(725 850);
PAINT GREEN (725 850);
FORCEPROP 2 LAST CUSTOM_TXT_CDS <XR_PAGE_TITLE>
J 0
(-5240 5750);
DISPLAY 0.638298 (-5240 5750);
PAINT PINK (-5240 5750);
DISPLAY INVISIBLE (-5240 5750);
FORCEPROP 1 LAST SCH_ADDRESS3 Santa Clara, CA 95052-8119
J 0
(-1325 525);
DISPLAY 0.617021 (-1325 525);
PAINT GREEN (-1325 525);
FORCEPROP 1 LAST SCH_ADDRESS2 P.O. BOX 58119
J 0
(-1325 575);
DISPLAY 0.617021 (-1325 575);
PAINT GREEN (-1325 575);
FORCEPROP 1 LAST SCH_ADDRESS1 2200 Mission College Blvd.
J 0
(-1325 625);
DISPLAY 0.617021 (-1325 625);
PAINT GREEN (-1325 625);
FORCEPROP 1 LAST SCH_TITLE CPU1 DDR4 CH K DIMM0
J 0
(-5300 550);
DISPLAY 1.212766 (-5300 550);
PAINT WHITE (-5300 550);
FORCEPROP 1 LAST SCH_NUMBER H4694802
J 0
(1350 650);
DISPLAY 1.212766 (1350 650);
PAINT YELLOW (1350 650);
FORCEPROP 1 LAST SCH_DEPT BESD
J 1
(-1800 600);
DISPLAY 1.212766 (-1800 600);
PAINT YELLOW (-1800 600);
FORCEPROP 1 LAST SCH_REV 2.420
J 0
(2400 650);
DISPLAY 0.978723 (2400 650);
PAINT YELLOW (2400 650);
FORCEPROP 2 LAST CDS_LIB mstr_symbols
J 0
(2650 500);
DISPLAY 0.787234 (2650 500);
PAINT MONO (2650 500);
DISPLAY INVISIBLE (2650 500);
FORCEPROP 2 LAST PAGE_BORDER TRUE
J 0
(-5240 5750);
DISPLAY 0.680851 (-5240 5750);
PAINT PINK (-5240 5750);
DISPLAY INVISIBLE (-5240 5750);
FORCEPROP 1 LAST COMMENT_BODY TRUE
J 0
(2660 510);
DISPLAY 0.382979 (2660 510);
PAINT GREEN (2660 510);
DISPLAY INVISIBLE (2660 510);
FORCEPROP 2 LAST CDS_XR_PAGE_TITLE CR-83 : @BASEBOARD_FAB2_LIB.BASEBOARD_FAB2(SCH_1):PAGE83
J 0
(-5240 5750);
DISPLAY 0.638298 (-5240 5750);
PAINT PINK (-5240 5750);
DISPLAY INVISIBLE (-5240 5750);
WIRE 17 -1 (950 5175)(950 5200);
WIRE 17 -1 (950 5075)(950 5175);
WIRE 17 -1 (1550 5200)(950 5200);
FORCEPROP 2 LAST SIG_NAME M_K_DQS_DN<17:0>
J 0
(1000 5210);
DISPLAY 0.617021 (1000 5210);
PAINT ORANGE (1000 5210);
WIRE 17 -1 (750 5225)(750 5250);
WIRE 17 -1 (750 5125)(750 5225);
WIRE 17 -1 (1550 5250)(750 5250);
FORCEPROP 2 LAST SIG_NAME M_K_DQS_DP<17:0>
J 0
(1000 5260);
DISPLAY 0.617021 (1000 5260);
PAINT ORANGE (1000 5260);
WIRE 17 -1 (950 4475)(950 4575);
WIRE 17 -1 (950 4375)(950 4475);
WIRE 17 -1 (950 4575)(950 4675);
WIRE 17 -1 (950 4675)(950 4775);
WIRE 17 -1 (950 4275)(950 4375);
WIRE 17 -1 (950 4175)(950 4275);
WIRE 17 -1 (950 4775)(950 4875);
WIRE 17 -1 (950 4875)(950 4975);
WIRE 17 -1 (950 4075)(950 4175);
WIRE 17 -1 (950 3975)(950 4075);
WIRE 17 -1 (950 4975)(950 5075);
WIRE 17 -1 (950 3875)(950 3975);
WIRE 17 -1 (950 3775)(950 3875);
WIRE 17 -1 (750 4525)(750 4625);
WIRE 17 -1 (750 4425)(750 4525);
WIRE 17 -1 (750 4625)(750 4725);
WIRE 17 -1 (750 4725)(750 4825);
WIRE 17 -1 (750 4325)(750 4425);
WIRE 17 -1 (750 4225)(750 4325);
WIRE 17 -1 (750 4825)(750 4925);
WIRE 17 -1 (750 4925)(750 5025);
WIRE 17 -1 (750 4125)(750 4225);
WIRE 17 -1 (750 4025)(750 4125);
WIRE 17 -1 (750 5025)(750 5125);
WIRE 17 -1 (750 3925)(750 4025);
WIRE 17 -1 (750 3825)(750 3925);
WIRE 17 -1 (750 3725)(750 3825);
WIRE 17 -1 (750 3625)(750 3725);
WIRE 17 -1 (750 3525)(750 3625);
WIRE 17 -1 (950 3675)(950 3775);
WIRE 17 -1 (950 3575)(950 3675);
WIRE 17 -1 (950 3475)(950 3575);
WIRE 17 -1 (-1650 4725)(-1650 4775);
WIRE 17 -1 (-1650 4675)(-1650 4725);
WIRE 17 -1 (-1650 4775)(-1650 4825);
WIRE 17 -1 (-1650 4825)(-1650 4875);
WIRE 17 -1 (-1650 4625)(-1650 4675);
WIRE 17 -1 (-1650 4575)(-1650 4625);
WIRE 17 -1 (-1650 4875)(-1650 4900);
WIRE 17 -1 (-1150 4900)(-1650 4900);
FORCEPROP 2 LAST SIG_NAME M_K_DQ<63:0>
J 0
(-1560 4910);
DISPLAY 0.617021 (-1560 4910);
PAINT ORANGE (-1560 4910);
WIRE 17 -1 (-1650 4525)(-1650 4575);
WIRE 17 -1 (-1650 4475)(-1650 4525);
WIRE 17 -1 (-1650 4425)(-1650 4475);
WIRE 17 -1 (-1650 4225)(-1650 4275);
WIRE 17 -1 (-1650 4175)(-1650 4225);
WIRE 17 -1 (-1650 4275)(-1650 4325);
WIRE 17 -1 (-1650 4325)(-1650 4375);
WIRE 17 -1 (-1650 4125)(-1650 4175);
WIRE 17 -1 (-1650 4075)(-1650 4125);
WIRE 17 -1 (-1650 4375)(-1650 4425);
WIRE 17 -1 (-1650 4025)(-1650 4075);
WIRE 17 -1 (-1650 3975)(-1650 4025);
WIRE 17 -1 (-1650 3925)(-1650 3975);
WIRE 17 -1 (-1650 3875)(-1650 3925);
WIRE 17 -1 (-1650 3825)(-1650 3875);
WIRE 17 -1 (-1650 3775)(-1650 3825);
WIRE 17 -1 (-1650 3725)(-1650 3775);
WIRE 17 -1 (-1650 3675)(-1650 3725);
WIRE 17 -1 (-1650 3625)(-1650 3675);
WIRE 17 -1 (-1650 3575)(-1650 3625);
WIRE 17 -1 (-1650 3525)(-1650 3575);
WIRE 17 -1 (-1650 3475)(-1650 3525);
WIRE 17 -1 (-1650 3425)(-1650 3475);
WIRE 17 -1 (-1650 3375)(-1650 3425);
WIRE 17 -1 (-3250 4225)(-3250 4275);
WIRE 17 -1 (-3250 4175)(-3250 4225);
WIRE 17 -1 (-3250 4275)(-3250 4325);
WIRE 17 -1 (-3250 4325)(-3250 4375);
WIRE 17 -1 (-3250 4125)(-3250 4175);
WIRE 17 -1 (-3250 4075)(-3250 4125);
WIRE 17 -1 (-3250 4375)(-3250 4425);
WIRE 17 -1 (-3250 4425)(-3250 4475);
WIRE 17 -1 (-3250 4025)(-3250 4075);
WIRE 17 -1 (-3250 4475)(-3250 4525);
WIRE 17 -1 (-3250 4525)(-3250 4575);
WIRE 17 -1 (-3250 4575)(-3250 4625);
WIRE 17 -1 (-3250 4625)(-3250 4675);
WIRE 17 -1 (-3250 4675)(-3250 4725);
WIRE 17 -1 (-3250 4725)(-3250 4775);
WIRE 17 -1 (-3250 4775)(-3250 4825);
WIRE 17 -1 (-3250 4825)(-3250 4875);
WIRE 17 -1 (-3250 4875)(-3250 4900);
WIRE 17 -1 (-3800 4900)(-3250 4900);
FORCEPROP 2 LAST SIG_NAME M_K_MA<17:0>
J 0
(-3775 4910);
DISPLAY 0.617021 (-3775 4910);
PAINT ORANGE (-3775 4910);
WIRE 17 -1 (-1650 3325)(-1650 3375);
WIRE 17 -1 (-1650 3275)(-1650 3325);
WIRE 17 -1 (-1650 3225)(-1650 3275);
WIRE 17 -1 (-1650 3175)(-1650 3225);
WIRE 17 -1 (-1650 3125)(-1650 3175);
WIRE 17 -1 (-1650 3075)(-1650 3125);
WIRE 17 -1 (-1650 3025)(-1650 3075);
WIRE 17 -1 (-1650 2975)(-1650 3025);
WIRE 17 -1 (-1650 2925)(-1650 2975);
WIRE 17 -1 (-1650 2875)(-1650 2925);
WIRE 17 -1 (-1650 2825)(-1650 2875);
WIRE 17 -1 (-1650 2775)(-1650 2825);
WIRE 17 -1 (-1650 2725)(-1650 2775);
WIRE 17 -1 (-1650 2675)(-1650 2725);
WIRE 17 -1 (-1650 2625)(-1650 2675);
WIRE 17 -1 (-1650 2575)(-1650 2625);
WIRE 17 -1 (-1650 2525)(-1650 2575);
WIRE 17 -1 (-1650 2475)(-1650 2525);
WIRE 17 -1 (-1650 2425)(-1650 2475);
WIRE 17 -1 (-1650 2375)(-1650 2425);
WIRE 17 -1 (-1650 2325)(-1650 2375);
WIRE 17 -1 (-1650 2275)(-1650 2325);
WIRE 17 -1 (-1650 2225)(-1650 2275);
WIRE 17 -1 (-1650 2175)(-1650 2225);
WIRE 17 -1 (-1650 2125)(-1650 2175);
WIRE 17 -1 (-1650 2075)(-1650 2125);
WIRE 17 -1 (-1650 2025)(-1650 2075);
WIRE 17 -1 (-1650 1975)(-1650 2025);
WIRE 17 -1 (-1650 1925)(-1650 1975);
WIRE 17 -1 (-1650 1875)(-1650 1925);
WIRE 17 -1 (-1650 1825)(-1650 1875);
WIRE 17 -1 (-1650 1775)(-1650 1825);
WIRE 17 -1 (-1650 1725)(-1650 1775);
WIRE 17 -1 (-3600 3750)(-3600 3675);
WIRE 17 -1 (-3600 3750)(-4200 3750);
FORCEPROP 2 LAST SIG_NAME M_K_CLK_DP<3:0>
J 0
(-4150 3760);
DISPLAY 0.617021 (-4150 3760);
PAINT ORANGE (-4150 3760);
WIRE 17 -1 (-3750 3625)(-3750 3700);
WIRE 17 -1 (-3750 3525)(-3750 3625);
WIRE 17 -1 (-3750 3700)(-4200 3700);
FORCEPROP 2 LAST SIG_NAME M_K_CLK_DN<3:0>
J 0
(-4150 3710);
DISPLAY 0.617021 (-4150 3710);
PAINT ORANGE (-4150 3710);
WIRE 17 -1 (-3600 3675)(-3600 3575);
WIRE 17 -1 (-3250 3775)(-3250 3825);
WIRE 17 -1 (-3250 3850)(-3250 3825);
WIRE 17 -1 (-3250 3850)(-3800 3850);
FORCEPROP 2 LAST SIG_NAME M_K_BG<1:0>
J 0
(-3775 3860);
DISPLAY 0.617021 (-3775 3860);
PAINT ORANGE (-3775 3860);
WIRE 17 -1 (-3250 3875)(-3250 3925);
WIRE 17 -1 (-3250 3950)(-3250 3925);
WIRE 17 -1 (-3250 3950)(-3800 3950);
FORCEPROP 2 LAST SIG_NAME M_K_BA<1:0>
J 0
(-3775 3960);
DISPLAY 0.617021 (-3775 3960);
PAINT ORANGE (-3775 3960);
WIRE 17 -1 (-3250 3375)(-3250 3400);
WIRE 17 -1 (-3250 3325)(-3250 3375);
WIRE 17 -1 (-3250 3400)(-3800 3400);
FORCEPROP 2 LAST SIG_NAME M_K_CS_N<7:0>
J 0
(-3775 3410);
DISPLAY 0.617021 (-3775 3410);
PAINT ORANGE (-3775 3410);
WIRE 17 -1 (-3250 3275)(-3250 3325);
WIRE 17 -1 (-3250 3225)(-3250 3275);
WIRE 17 -1 (-3250 2775)(-3250 2825);
WIRE 17 -1 (-3250 2725)(-3250 2775);
WIRE 17 -1 (-3250 2825)(-3250 2850);
WIRE 17 -1 (-3250 2850)(-3800 2850);
FORCEPROP 2 LAST SIG_NAME M_K_ECC<7:0>
J 0
(-3775 2860);
DISPLAY 0.617021 (-3775 2860);
PAINT ORANGE (-3775 2860);
WIRE 17 -1 (-3250 2675)(-3250 2725);
WIRE 17 -1 (-3250 2625)(-3250 2675);
WIRE 17 -1 (-3250 2575)(-3250 2625);
WIRE 17 -1 (-3250 2525)(-3250 2575);
WIRE 17 -1 (-3250 2475)(-3250 2525);
WIRE 17 -1 (-3250 3125)(-3250 3150);
WIRE 17 -1 (-3250 3075)(-3250 3125);
WIRE 17 -1 (-3250 3150)(-3800 3150);
FORCEPROP 2 LAST SIG_NAME M_K_CKE<3:0>
J 0
(-3775 3160);
DISPLAY 0.617021 (-3775 3160);
PAINT ORANGE (-3775 3160);
WIRE 17 -1 (-3250 2925)(-3250 2975);
WIRE 17 -1 (-3250 2975)(-3250 3000);
WIRE 17 -1 (-3250 3000)(-3800 3000);
FORCEPROP 2 LAST SIG_NAME M_K_ODT<3:0>
J 0
(-3775 3010);
DISPLAY 0.617021 (-3775 3010);
PAINT ORANGE (-3775 3010);
WIRE 16 -1 (-850 1250)(-650 1250);
WIRE 16 -1 (-850 1250)(-850 1300);
WIRE 16 -1 (-850 1300)(-650 1300);
WIRE 16 -1 (-850 1300)(-850 1350);
WIRE 16 -1 (-850 1350)(-650 1350);
WIRE 16 -1 (-850 1350)(-850 1400);
WIRE 16 -1 (-850 1400)(-650 1400);
WIRE 16 -1 (-850 1400)(-850 1450);
WIRE 16 -1 (-850 1450)(-650 1450);
WIRE 16 -1 (-850 1450)(-850 1500);
WIRE 16 -1 (-850 1500)(-850 1550);
WIRE 16 -1 (-850 1500)(-650 1500);
WIRE 16 -1 (-850 1550)(-650 1550);
WIRE 16 -1 (-850 1550)(-850 1600);
WIRE 16 -1 (-850 1600)(-650 1600);
WIRE 16 -1 (-850 1600)(-850 1650);
WIRE 16 -1 (-850 1650)(-650 1650);
WIRE 16 -1 (-850 1650)(-850 1700);
WIRE 16 -1 (-850 1700)(-650 1700);
WIRE 16 -1 (-850 1700)(-850 1750);
WIRE 16 -1 (-850 1750)(-650 1750);
WIRE 16 -1 (-850 1750)(-850 1800);
WIRE 16 -1 (-850 1800)(-650 1800);
WIRE 16 -1 (-850 1800)(-850 1850);
WIRE 16 -1 (-850 1850)(-650 1850);
WIRE 16 -1 (-850 1850)(-850 1900);
WIRE 16 -1 (-850 1900)(-650 1900);
WIRE 16 -1 (-850 1900)(-850 1950);
WIRE 16 -1 (-850 1950)(-650 1950);
WIRE 16 -1 (-850 1950)(-850 2000);
WIRE 16 -1 (-850 2000)(-850 2050);
WIRE 16 -1 (-850 2000)(-650 2000);
WIRE 16 -1 (-850 2050)(-650 2050);
WIRE 16 -1 (-850 2050)(-850 2100);
WIRE 16 -1 (-850 2100)(-650 2100);
WIRE 16 -1 (-850 2100)(-850 2150);
WIRE 16 -1 (-850 2150)(-650 2150);
WIRE 16 -1 (-850 2150)(-850 2200);
WIRE 16 -1 (-850 2200)(-650 2200);
WIRE 16 -1 (-850 2200)(-850 2250);
WIRE 16 -1 (-850 2250)(-650 2250);
WIRE 16 -1 (-850 2250)(-850 2300);
WIRE 16 -1 (-850 2300)(-650 2300);
WIRE 16 -1 (-850 2300)(-850 2350);
WIRE 16 -1 (-850 2350)(-650 2350);
WIRE 16 -1 (-850 2350)(-850 2400);
WIRE 16 -1 (-850 2400)(-650 2400);
WIRE 16 -1 (-850 2400)(-850 2450);
WIRE 16 -1 (-850 2450)(-650 2450);
WIRE 16 -1 (-850 2450)(-850 2500);
WIRE 16 -1 (-850 2500)(-650 2500);
WIRE 16 -1 (-1300 2500)(-850 2500);
WIRE 16 -1 (-1300 2575)(-1300 2500);
WIRE 16 -1 (2500 3500)(2500 3550);
WIRE 16 -1 (2500 3450)(2500 3500);
WIRE 16 -1 (2500 3500)(2300 3500);
WIRE 16 -1 (2500 3550)(2300 3550);
WIRE 16 -1 (2500 3400)(2500 3450);
WIRE 16 -1 (2500 3450)(2300 3450);
WIRE 16 -1 (2500 3350)(2500 3400);
WIRE 16 -1 (2500 3400)(2300 3400);
WIRE 16 -1 (2500 3300)(2500 3350);
WIRE 16 -1 (2500 3350)(2300 3350);
WIRE 16 -1 (2500 3250)(2500 3300);
WIRE 16 -1 (2500 3300)(2300 3300);
WIRE 16 -1 (2500 3200)(2500 3250);
WIRE 16 -1 (2500 3250)(2300 3250);
WIRE 16 -1 (2500 3150)(2500 3200);
WIRE 16 -1 (2500 3200)(2300 3200);
WIRE 16 -1 (2500 3100)(2500 3150);
WIRE 16 -1 (2500 3150)(2300 3150);
WIRE 16 -1 (2500 3100)(2300 3100);
WIRE 16 -1 (2500 3050)(2500 3100);
WIRE 16 -1 (2500 3000)(2500 3050);
WIRE 16 -1 (2500 3050)(2300 3050);
WIRE 16 -1 (2500 2950)(2500 3000);
WIRE 16 -1 (2500 3000)(2300 3000);
WIRE 16 -1 (2500 2900)(2500 2950);
WIRE 16 -1 (2500 2950)(2300 2950);
WIRE 16 -1 (2500 2850)(2500 2900);
WIRE 16 -1 (2500 2900)(2300 2900);
WIRE 16 -1 (2500 2800)(2500 2850);
WIRE 16 -1 (2500 2850)(2300 2850);
WIRE 16 -1 (2500 2750)(2500 2800);
WIRE 16 -1 (2500 2800)(2300 2800);
WIRE 16 -1 (2500 2700)(2500 2750);
WIRE 16 -1 (2500 2750)(2300 2750);
WIRE 16 -1 (2500 2650)(2500 2700);
WIRE 16 -1 (2500 2700)(2300 2700);
WIRE 16 -1 (2500 2600)(2500 2650);
WIRE 16 -1 (2500 2650)(2300 2650);
WIRE 16 -1 (2500 2600)(2300 2600);
WIRE 16 -1 (2500 2550)(2500 2600);
WIRE 16 -1 (2500 2500)(2500 2550);
WIRE 16 -1 (2500 2550)(2300 2550);
WIRE 16 -1 (2500 2450)(2500 2500);
WIRE 16 -1 (2500 2500)(2300 2500);
WIRE 16 -1 (2500 2400)(2500 2450);
WIRE 16 -1 (2500 2450)(2300 2450);
WIRE 16 -1 (2500 2350)(2500 2400);
WIRE 16 -1 (2500 2400)(2300 2400);
WIRE 16 -1 (2500 2300)(2500 2350);
WIRE 16 -1 (2500 2350)(2300 2350);
WIRE 16 -1 (2500 2250)(2500 2300);
WIRE 16 -1 (2500 2300)(2300 2300);
WIRE 16 -1 (2500 2200)(2500 2250);
WIRE 16 -1 (2500 2250)(2300 2250);
WIRE 16 -1 (2500 2150)(2500 2200);
WIRE 16 -1 (2500 2200)(2300 2200);
WIRE 16 -1 (2500 2100)(2500 2150);
WIRE 16 -1 (2500 2150)(2300 2150);
WIRE 16 -1 (2500 2050)(2500 2100);
WIRE 16 -1 (2500 2100)(2300 2100);
WIRE 16 -1 (2500 2050)(2300 2050);
WIRE 16 -1 (2500 2000)(2500 2050);
WIRE 16 -1 (2500 1950)(2500 2000);
WIRE 16 -1 (2500 2000)(2300 2000);
WIRE 16 -1 (2500 1900)(2500 1950);
WIRE 16 -1 (2500 1950)(2300 1950);
WIRE 16 -1 (2500 1850)(2500 1900);
WIRE 16 -1 (2500 1900)(2300 1900);
WIRE 16 -1 (2500 1800)(2500 1850);
WIRE 16 -1 (2500 1850)(2300 1850);
WIRE 16 -1 (2500 1750)(2500 1800);
WIRE 16 -1 (2500 1800)(2300 1800);
WIRE 16 -1 (2500 1700)(2500 1750);
WIRE 16 -1 (2500 1750)(2300 1750);
WIRE 16 -1 (2500 1650)(2500 1700);
WIRE 16 -1 (2500 1700)(2300 1700);
WIRE 16 -1 (2500 1600)(2500 1650);
WIRE 16 -1 (2500 1650)(2300 1650);
WIRE 16 -1 (2500 1550)(2500 1600);
WIRE 16 -1 (2500 1600)(2300 1600);
WIRE 16 -1 (2500 1550)(2300 1550);
WIRE 16 -1 (2500 1500)(2500 1550);
WIRE 16 -1 (2500 1450)(2500 1500);
WIRE 16 -1 (2500 1500)(2300 1500);
WIRE 16 -1 (2500 1400)(2500 1450);
WIRE 16 -1 (2500 1450)(2300 1450);
WIRE 16 -1 (2500 1350)(2500 1400);
WIRE 16 -1 (2500 1400)(2300 1400);
WIRE 16 -1 (2500 1300)(2500 1350);
WIRE 16 -1 (2500 1350)(2300 1350);
WIRE 16 -1 (2500 1250)(2500 1300);
WIRE 16 -1 (2500 1300)(2300 1300);
WIRE 16 -1 (2500 1150)(2500 1250);
WIRE 16 -1 (2500 1250)(2300 1250);
WIRE 16 -1 (-850 2600)(-650 2600);
WIRE 16 -1 (-850 2600)(-850 2650);
WIRE 16 -1 (-850 2650)(-650 2650);
WIRE 16 -1 (-1050 2650)(-850 2650);
WIRE 16 -1 (-1050 2750)(-1050 2650);
WIRE 16 -1 (-2950 1900)(-3150 1900);
WIRE 16 -1 (-3150 1900)(-3150 1950);
WIRE 16 -1 (-3150 1950)(-2950 1950);
WIRE 16 -1 (-3150 1950)(-3150 2000);
WIRE 16 -1 (-2950 2000)(-3150 2000);
WIRE 16 -1 (-3150 2000)(-5100 2000);
WIRE 16 -1 (-5100 2000)(-5100 1900);
WIRE 16 -1 (-4600 1400)(-4600 1300);
WIRE 16 -1 (-850 2750)(-650 2750);
WIRE 16 -1 (-850 2800)(-850 2750);
WIRE 16 -1 (-850 2800)(-650 2800);
WIRE 16 -1 (-850 2850)(-850 2800);
WIRE 16 -1 (-850 2850)(-650 2850);
WIRE 16 -1 (-850 2850)(-850 2900);
WIRE 16 -1 (-850 2900)(-650 2900);
WIRE 16 -1 (-850 2950)(-850 2900);
WIRE 16 -1 (-850 2950)(-650 2950);
WIRE 16 -1 (-850 3050)(-850 2950);
WIRE 16 -1 (-5100 2050)(-2950 2050);
WIRE 16 -1 (-5100 2050)(-5100 2150);
WIRE 16 -1 (550 2900)(550 2950);
WIRE 16 -1 (550 2900)(350 2900);
WIRE 16 -1 (550 2950)(550 3125);
WIRE 16 -1 (550 2950)(350 2950);
WIRE 16 -1 (1100 3550)(1300 3550);
WIRE 16 -1 (1100 3500)(1100 3550);
WIRE 16 -1 (1100 3500)(1300 3500);
WIRE 16 -1 (1100 3450)(1100 3500);
WIRE 16 -1 (1100 3450)(1300 3450);
WIRE 16 -1 (1100 3400)(1100 3450);
WIRE 16 -1 (1100 3400)(1300 3400);
WIRE 16 -1 (1100 3350)(1100 3400);
WIRE 16 -1 (1100 3350)(1300 3350);
WIRE 16 -1 (1100 3300)(1100 3350);
WIRE 16 -1 (1100 3300)(1300 3300);
WIRE 16 -1 (1100 3250)(1100 3300);
WIRE 16 -1 (1100 3250)(1300 3250);
WIRE 16 -1 (1100 3200)(1100 3250);
WIRE 16 -1 (1100 3200)(1300 3200);
WIRE 16 -1 (1100 3150)(1100 3200);
WIRE 16 -1 (1100 3150)(1300 3150);
WIRE 16 -1 (1100 3100)(1100 3150);
WIRE 16 -1 (1100 3100)(1300 3100);
WIRE 16 -1 (1100 3050)(1100 3100);
WIRE 16 -1 (1100 3050)(1300 3050);
WIRE 16 -1 (1100 3000)(1100 3050);
WIRE 16 -1 (1100 3000)(1300 3000);
WIRE 16 -1 (1100 2950)(1100 3000);
WIRE 16 -1 (1100 2950)(1300 2950);
WIRE 16 -1 (1100 2900)(1100 2950);
WIRE 16 -1 (1100 2900)(1300 2900);
WIRE 16 -1 (1100 2850)(1100 2900);
WIRE 16 -1 (1100 2850)(1300 2850);
WIRE 16 -1 (1100 2800)(1100 2850);
WIRE 16 -1 (1100 2800)(1300 2800);
WIRE 16 -1 (1100 2750)(1100 2800);
WIRE 16 -1 (1100 2750)(1300 2750);
WIRE 16 -1 (1100 2700)(1100 2750);
WIRE 16 -1 (1100 2700)(1300 2700);
WIRE 16 -1 (1100 2650)(1100 2700);
WIRE 16 -1 (1100 2650)(1300 2650);
WIRE 16 -1 (1100 2600)(1100 2650);
WIRE 16 -1 (1100 2600)(1300 2600);
WIRE 16 -1 (1100 2550)(1100 2600);
WIRE 16 -1 (1100 2550)(1300 2550);
WIRE 16 -1 (1100 2500)(1100 2550);
WIRE 16 -1 (1100 2500)(1300 2500);
WIRE 16 -1 (1100 2450)(1100 2500);
WIRE 16 -1 (1100 2450)(1300 2450);
WIRE 16 -1 (1100 2400)(1100 2450);
WIRE 16 -1 (1100 2400)(1300 2400);
WIRE 16 -1 (1100 2350)(1100 2400);
WIRE 16 -1 (1100 2350)(1300 2350);
WIRE 16 -1 (1100 2300)(1100 2350);
WIRE 16 -1 (1100 2300)(1300 2300);
WIRE 16 -1 (1100 2250)(1100 2300);
WIRE 16 -1 (1100 2250)(1300 2250);
WIRE 16 -1 (1100 2200)(1100 2250);
WIRE 16 -1 (1100 2200)(1300 2200);
WIRE 16 -1 (1100 2150)(1100 2200);
WIRE 16 -1 (1100 2150)(1300 2150);
WIRE 16 -1 (1100 2100)(1100 2150);
WIRE 16 -1 (1100 2100)(1300 2100);
WIRE 16 -1 (1100 2050)(1100 2100);
WIRE 16 -1 (1100 2050)(1300 2050);
WIRE 16 -1 (1100 2000)(1100 2050);
WIRE 16 -1 (1100 2000)(1300 2000);
WIRE 16 -1 (1100 1950)(1100 2000);
WIRE 16 -1 (1100 1950)(1300 1950);
WIRE 16 -1 (1100 1900)(1100 1950);
WIRE 16 -1 (1100 1900)(1300 1900);
WIRE 16 -1 (1100 1850)(1100 1900);
WIRE 16 -1 (1100 1850)(1300 1850);
WIRE 16 -1 (1100 1800)(1100 1850);
WIRE 16 -1 (1100 1800)(1300 1800);
WIRE 16 -1 (1100 1750)(1100 1800);
WIRE 16 -1 (1100 1750)(1300 1750);
WIRE 16 -1 (1100 1700)(1100 1750);
WIRE 16 -1 (1100 1700)(1300 1700);
WIRE 16 -1 (1100 1650)(1100 1700);
WIRE 16 -1 (1100 1650)(1300 1650);
WIRE 16 -1 (1100 1600)(1100 1650);
WIRE 16 -1 (1100 1600)(1300 1600);
WIRE 16 -1 (1100 1550)(1100 1600);
WIRE 16 -1 (1100 1550)(1300 1550);
WIRE 16 -1 (1100 1500)(1100 1550);
WIRE 16 -1 (1100 1500)(1300 1500);
WIRE 16 -1 (1100 1450)(1100 1500);
WIRE 16 -1 (1100 1450)(1300 1450);
WIRE 16 -1 (1100 1400)(1100 1450);
WIRE 16 -1 (1100 1400)(1300 1400);
WIRE 16 -1 (1100 1350)(1100 1400);
WIRE 16 -1 (1100 1350)(1300 1350);
WIRE 16 -1 (1100 1300)(1100 1350);
WIRE 16 -1 (1100 1300)(1300 1300);
WIRE 16 -1 (1100 1250)(1100 1300);
WIRE 16 -1 (1100 1250)(1300 1250);
WIRE 16 -1 (1100 1150)(1100 1250);
WIRE 16 -1 (-2950 2200)(-3975 2200);
FORCEPROP 2 LAST SIG_NAME M_K_ALERT_N
J 0
(-3925 2210);
DISPLAY 0.617021 (-3925 2210);
PAINT ORANGE (-3925 2210);
WIRE 16 -1 (-2950 1700)(-4600 1700);
FORCEPROP 2 LAST SIG_NAME M_K_VREF
J 0
(-3700 1710);
DISPLAY 0.617021 (-3700 1710);
PAINT ORANGE (-3700 1710);
WIRE 16 -1 (-4600 1700)(-4600 1600);
WIRE 16 -1 (-4700 1700)(-4600 1700);
WIRE 16 -1 (-3800 1550)(-2950 1550);
FORCEPROP 2 LAST SIG_NAME TP_CH_K_DIMM_K0_RFU_1
J 0
(-3750 1560);
DISPLAY 0.617021 (-3750 1560);
PAINT ORANGE (-3750 1560);
FORCEPROP 2 LASTPROP $XRERR UNIQUE?
J 0
(-4040 1550);
DISPLAY 0.638298 (-4040 1550);
PAINT MONO (-4040 1550);
DISPLAY INVISIBLE (-4040 1550);
WIRE 16 -1 (-3800 1500)(-2950 1500);
FORCEPROP 2 LAST SIG_NAME TP_CH_K_DIMM_K0_RFU_0
J 0
(-3750 1510);
DISPLAY 0.617021 (-3750 1510);
PAINT ORANGE (-3750 1510);
FORCEPROP 2 LASTPROP $XRERR UNIQUE?
J 0
(-4040 1500);
DISPLAY 0.638298 (-4040 1500);
PAINT MONO (-4040 1500);
DISPLAY INVISIBLE (-4040 1500);
WIRE 16 -1 (-3800 1600)(-2950 1600);
FORCEPROP 2 LAST SIG_NAME TP_CH_K_DIMM_K0_RFU_2
J 0
(-3750 1610);
DISPLAY 0.617021 (-3750 1610);
PAINT ORANGE (-3750 1610);
FORCEPROP 2 LASTPROP $XRERR UNIQUE?
J 0
(-4040 1600);
DISPLAY 0.638298 (-4040 1600);
PAINT MONO (-4040 1600);
DISPLAY INVISIBLE (-4040 1600);
WIRE 16 -1 (-2950 1850)(-3750 1850);
WIRE 16 -1 (-3750 1800)(-2950 1800);
FORCEPROP 2 LAST SIG_NAME SMB_DDR_KLM_VPP_SCL
J 0
(-3710 1810);
DISPLAY 0.617021 (-3710 1810);
PAINT ORANGE (-3710 1810);
WIRE 16 -1 (-3800 1400)(-2950 1400);
FORCEPROP 2 LAST SIG_NAME FM_ADR_COMPLETE_KLM_N
J 0
(-3750 1410);
DISPLAY 0.617021 (-3750 1410);
PAINT ORANGE (-3750 1410);
WIRE 16 -1 (-3400 2250)(-2950 2250);
WIRE 16 -1 (-3400 2550)(-3400 2250);
WIRE 16 -1 (-3400 2550)(-4125 2550);
FORCEPROP 2 LAST SIG_NAME FM_DIMM_EVENT_COD_N
J 0
(-4103 2563);
DISPLAY 0.617021 (-4103 2563);
PAINT ORANGE (-4103 2563);
WIRE 16 -1 (-2950 2300)(-3350 2300);
WIRE 16 -1 (-3350 2300)(-3350 2750);
WIRE 16 -1 (-3350 2750)(-3800 2750);
FORCEPROP 2 LAST SIG_NAME M_KLM_RST_N
J 0
(-3775 2760);
DISPLAY 0.617021 (-3775 2760);
PAINT ORANGE (-3775 2760);
WIRE 16 -1 (-2950 2350)(-3300 2350);
WIRE 16 -1 (-3300 2350)(-3300 2800);
WIRE 16 -1 (-3300 2800)(-3800 2800);
FORCEPROP 2 LAST SIG_NAME M_K_PAR
J 0
(-3775 2810);
DISPLAY 0.617021 (-3775 2810);
PAINT ORANGE (-3775 2810);
WIRE 16 -1 (-3100 3400)(-2950 3400);
WIRE 16 -1 (-3100 3450)(-3100 3400);
WIRE 16 -1 (-3100 3450)(-3800 3450);
FORCEPROP 2 LAST SIG_NAME M_K_C<2>
J 0
(-3775 3460);
DISPLAY 0.617021 (-3775 3460);
PAINT ORANGE (-3775 3460);
WIRE 16 -1 (-2950 3200)(-3150 3200);
WIRE 16 -1 (-2950 3050)(-3150 3050);
WIRE 16 -1 (-2950 2950)(-3150 2950);
WIRE 16 -1 (-2950 2900)(-3150 2900);
WIRE 16 -1 (-2950 2800)(-3150 2800);
WIRE 16 -1 (-2950 3850)(-3150 3850);
WIRE 16 -1 (-2950 3800)(-3150 3800);
WIRE 16 -1 (-2950 3100)(-3150 3100);
WIRE 16 -1 (-2950 2450)(-3150 2450);
WIRE 16 -1 (-2950 2500)(-3150 2500);
WIRE 16 -1 (-2950 2550)(-3150 2550);
WIRE 16 -1 (-2950 2600)(-3150 2600);
WIRE 16 -1 (-2950 2650)(-3150 2650);
WIRE 16 -1 (-2950 2700)(-3150 2700);
WIRE 16 -1 (-2950 2750)(-3150 2750);
WIRE 16 -1 (-2950 4050)(-3150 4050);
WIRE 16 -1 (-2950 4000)(-3150 4000);
WIRE 16 -1 (-2950 3250)(-3150 3250);
WIRE 16 -1 (-2950 3300)(-3150 3300);
WIRE 16 -1 (-2950 3350)(-3150 3350);
WIRE 16 -1 (-2950 3900)(-3150 3900);
WIRE 16 -1 (-2950 3750)(-3150 3750);
WIRE 16 -1 (-2950 3500)(-3650 3500);
WIRE 16 -1 (-2950 3550)(-3500 3550);
WIRE 16 -1 (-2950 3600)(-3650 3600);
WIRE 16 -1 (-2950 3650)(-3500 3650);
WIRE 16 -1 (-2950 2150)(-3950 2150);
FORCEPROP 2 LAST SIG_NAME M_K_ACT_N
J 0
(-3900 2160);
DISPLAY 0.617021 (-3900 2160);
PAINT ORANGE (-3900 2160);
WIRE 16 -1 (-1750 1950)(-1950 1950);
WIRE 16 -1 (-1750 1900)(-1950 1900);
WIRE 16 -1 (-1750 1850)(-1950 1850);
WIRE 16 -1 (-1750 1800)(-1950 1800);
WIRE 16 -1 (-1750 1700)(-1950 1700);
WIRE 16 -1 (-1750 1750)(-1950 1750);
WIRE 16 -1 (-1750 2000)(-1950 2000);
WIRE 16 -1 (-1750 2550)(-1950 2550);
WIRE 16 -1 (-1750 2450)(-1950 2450);
WIRE 16 -1 (-1750 2050)(-1950 2050);
WIRE 16 -1 (-1750 2100)(-1950 2100);
WIRE 16 -1 (-1750 2150)(-1950 2150);
WIRE 16 -1 (-1750 2200)(-1950 2200);
WIRE 16 -1 (-1750 2250)(-1950 2250);
WIRE 16 -1 (-1750 2300)(-1950 2300);
WIRE 16 -1 (-1750 2350)(-1950 2350);
WIRE 16 -1 (-1750 2400)(-1950 2400);
WIRE 16 -1 (-1750 2500)(-1950 2500);
WIRE 16 -1 (-1750 3000)(-1950 3000);
WIRE 16 -1 (-1750 3050)(-1950 3050);
WIRE 16 -1 (-1750 2600)(-1950 2600);
WIRE 16 -1 (-1750 2650)(-1950 2650);
WIRE 16 -1 (-1750 2700)(-1950 2700);
WIRE 16 -1 (-1750 2750)(-1950 2750);
WIRE 16 -1 (-1750 2850)(-1950 2850);
WIRE 16 -1 (-1750 2900)(-1950 2900);
WIRE 16 -1 (-1750 2950)(-1950 2950);
WIRE 16 -1 (-1750 2800)(-1950 2800);
WIRE 16 -1 (-1750 3500)(-1950 3500);
WIRE 16 -1 (-1750 3450)(-1950 3450);
WIRE 16 -1 (-1750 3200)(-1950 3200);
WIRE 16 -1 (-1750 3250)(-1950 3250);
WIRE 16 -1 (-1750 3300)(-1950 3300);
WIRE 16 -1 (-1750 3350)(-1950 3350);
WIRE 16 -1 (-1750 3400)(-1950 3400);
WIRE 16 -1 (-1750 3550)(-1950 3550);
WIRE 16 -1 (-1750 3100)(-1950 3100);
WIRE 16 -1 (-1750 3150)(-1950 3150);
WIRE 16 -1 (-1750 4050)(-1950 4050);
WIRE 16 -1 (-1750 3600)(-1950 3600);
WIRE 16 -1 (-1750 3650)(-1950 3650);
WIRE 16 -1 (-1750 3700)(-1950 3700);
WIRE 16 -1 (-1750 3750)(-1950 3750);
WIRE 16 -1 (-1750 3800)(-1950 3800);
WIRE 16 -1 (-1750 3850)(-1950 3850);
WIRE 16 -1 (-1750 3900)(-1950 3900);
WIRE 16 -1 (-1750 3950)(-1950 3950);
WIRE 16 -1 (-1750 4000)(-1950 4000);
WIRE 16 -1 (-2950 4800)(-3150 4800);
WIRE 16 -1 (-2950 4750)(-3150 4750);
WIRE 16 -1 (-2950 4700)(-3150 4700);
WIRE 16 -1 (-2950 4550)(-3150 4550);
WIRE 16 -1 (-2950 4500)(-3150 4500);
WIRE 16 -1 (-2950 4100)(-3150 4100);
WIRE 16 -1 (-2950 4450)(-3150 4450);
WIRE 16 -1 (-2950 4400)(-3150 4400);
WIRE 16 -1 (-2950 4350)(-3150 4350);
WIRE 16 -1 (-2950 4300)(-3150 4300);
WIRE 16 -1 (-2950 4250)(-3150 4250);
WIRE 16 -1 (-2950 4150)(-3150 4150);
WIRE 16 -1 (-2950 4850)(-3150 4850);
WIRE 16 -1 (-2950 4650)(-3150 4650);
WIRE 16 -1 (-2950 4600)(-3150 4600);
WIRE 16 -1 (-2950 4200)(-3150 4200);
WIRE 16 -1 (-1750 4100)(-1950 4100);
WIRE 16 -1 (-1750 4150)(-1950 4150);
WIRE 16 -1 (-1750 4300)(-1950 4300);
WIRE 16 -1 (-1750 4350)(-1950 4350);
WIRE 16 -1 (-1750 4400)(-1950 4400);
WIRE 16 -1 (-1750 4600)(-1950 4600);
WIRE 16 -1 (-1750 4550)(-1950 4550);
WIRE 16 -1 (-1750 4450)(-1950 4450);
WIRE 16 -1 (-1750 4500)(-1950 4500);
WIRE 16 -1 (-1750 4250)(-1950 4250);
WIRE 16 -1 (-1750 4200)(-1950 4200);
WIRE 16 -1 (-1750 4850)(-1950 4850);
WIRE 16 -1 (-1750 4800)(-1950 4800);
WIRE 16 -1 (-1750 4750)(-1950 4750);
WIRE 16 -1 (-1750 4650)(-1950 4650);
WIRE 16 -1 (-1750 4700)(-1950 4700);
WIRE 16 -1 (850 4050)(450 4050);
WIRE 16 -1 (650 4000)(450 4000);
WIRE 16 -1 (850 3950)(450 3950);
WIRE 16 -1 (650 3900)(450 3900);
WIRE 16 -1 (850 3850)(450 3850);
WIRE 16 -1 (650 3800)(450 3800);
WIRE 16 -1 (850 3750)(450 3750);
WIRE 16 -1 (650 3700)(450 3700);
WIRE 16 -1 (850 3650)(450 3650);
WIRE 16 -1 (650 3600)(450 3600);
WIRE 16 -1 (850 3550)(450 3550);
WIRE 16 -1 (650 3500)(450 3500);
WIRE 16 -1 (850 3450)(450 3450);
WIRE 16 -1 (650 4400)(450 4400);
WIRE 16 -1 (850 4350)(450 4350);
WIRE 16 -1 (650 4300)(450 4300);
WIRE 16 -1 (850 4250)(450 4250);
WIRE 16 -1 (650 4200)(450 4200);
WIRE 16 -1 (850 4150)(450 4150);
WIRE 16 -1 (650 4100)(450 4100);
WIRE 16 -1 (650 5100)(450 5100);
WIRE 16 -1 (850 5050)(450 5050);
WIRE 16 -1 (650 5000)(450 5000);
WIRE 16 -1 (850 4950)(450 4950);
WIRE 16 -1 (650 4900)(450 4900);
WIRE 16 -1 (850 4850)(450 4850);
WIRE 16 -1 (650 4800)(450 4800);
WIRE 16 -1 (850 4750)(450 4750);
WIRE 16 -1 (650 4700)(450 4700);
WIRE 16 -1 (850 4650)(450 4650);
WIRE 16 -1 (650 4600)(450 4600);
WIRE 16 -1 (850 4550)(450 4550);
WIRE 16 -1 (650 4500)(450 4500);
WIRE 16 -1 (850 4450)(450 4450);
WIRE 16 -1 (650 5200)(450 5200);
WIRE 16 -1 (850 5150)(450 5150);
DOT 1 (-850 2450);
DOT 1 (1100 2600);
DOT 1 (1100 2700);
DOT 1 (1100 3100);
DOT 1 (1100 1550);
DOT 1 (-3150 1950);
DOT 1 (-3150 2000);
DOT 1 (-850 2800);
DOT 1 (-850 1300);
DOT 1 (-850 2100);
DOT 1 (-850 2150);
DOT 1 (-850 2200);
DOT 1 (-850 1350);
DOT 1 (-850 1500);
DOT 1 (-850 1450);
DOT 1 (-850 1400);
DOT 1 (-850 1600);
DOT 1 (-850 1550);
DOT 1 (-850 1650);
DOT 1 (-850 1700);
DOT 1 (-850 1750);
DOT 1 (-850 1850);
DOT 1 (-850 1800);
DOT 1 (-850 1900);
DOT 1 (-850 2000);
DOT 1 (-850 1950);
DOT 1 (-850 2050);
DOT 1 (-850 2250);
DOT 1 (-850 2300);
DOT 1 (-850 2350);
DOT 1 (-850 2400);
DOT 1 (-850 2500);
DOT 1 (-850 2850);
DOT 1 (1100 1250);
DOT 1 (1100 1300);
DOT 1 (1100 1400);
DOT 1 (1100 1350);
DOT 1 (1100 1500);
DOT 1 (1100 1450);
DOT 1 (1100 1650);
DOT 1 (1100 1600);
DOT 1 (1100 1750);
DOT 1 (1100 1700);
DOT 1 (1100 1800);
DOT 1 (1100 1900);
DOT 1 (1100 1850);
DOT 1 (1100 2000);
DOT 1 (1100 2150);
DOT 1 (1100 2100);
DOT 1 (1100 2200);
DOT 1 (1100 2250);
DOT 1 (1100 2300);
DOT 1 (1100 2400);
DOT 1 (1100 2350);
DOT 1 (1100 2450);
DOT 1 (1100 2500);
DOT 1 (1100 2650);
DOT 1 (1100 2750);
DOT 1 (1100 2900);
DOT 1 (1100 2850);
DOT 1 (1100 2950);
DOT 1 (1100 3000);
DOT 1 (1100 3200);
DOT 1 (1100 3150);
DOT 1 (1100 3250);
DOT 1 (1100 3300);
DOT 1 (1100 3350);
DOT 1 (1100 3450);
DOT 1 (1100 3400);
DOT 1 (1100 3500);
DOT 1 (2500 3500);
DOT 1 (2500 3350);
DOT 1 (2500 3450);
DOT 1 (2500 3400);
DOT 1 (2500 3250);
DOT 1 (2500 3300);
DOT 1 (2500 3200);
DOT 1 (2500 3100);
DOT 1 (2500 3150);
DOT 1 (2500 3000);
DOT 1 (2500 3050);
DOT 1 (2500 2950);
DOT 1 (2500 2850);
DOT 1 (2500 2900);
DOT 1 (2500 2750);
DOT 1 (2500 2800);
DOT 1 (2500 2700);
DOT 1 (2500 2600);
DOT 1 (2500 2650);
DOT 1 (2500 2450);
DOT 1 (2500 2550);
DOT 1 (2500 2500);
DOT 1 (2500 2350);
DOT 1 (2500 2400);
DOT 1 (2500 2200);
DOT 1 (2500 2250);
DOT 1 (2500 2300);
DOT 1 (2500 2100);
DOT 1 (2500 2150);
DOT 1 (2500 2050);
DOT 1 (2500 2000);
DOT 1 (2500 1950);
DOT 1 (2500 1850);
DOT 1 (2500 1900);
DOT 1 (2500 1800);
DOT 1 (2500 1750);
DOT 1 (2500 1700);
DOT 1 (2500 1650);
DOT 1 (2500 1600);
DOT 1 (2500 1550);
DOT 1 (2500 1500);
DOT 1 (2500 1450);
DOT 1 (2500 1300);
DOT 1 (2500 1400);
DOT 1 (2500 1350);
DOT 1 (2500 1250);
DOT 1 (-4600 1700);
DOT 1 (1100 3050);
DOT 1 (550 2950);
DOT 1 (-850 2650);
DOT 1 (-850 2950);
DOT 1 (1100 2800);
DOT 1 (1100 2550);
DOT 1 (1100 2050);
DOT 1 (1100 1950);
DOT 1 (-850 2900);
FORCENOTE
SMBUS ADDR: 0XA0
(-5275 1009) 0;
DISPLAY LEFT (-5275 1009);
DISPLAY 1.957447 (-5275 1009);
PAINT PURPLE (-5275 1009);
FORCENOTE
PLACE CAP NEAR DIMM CONNECTOR
(-5288 1152) 0;
DISPLAY LEFT (-5288 1152);
DISPLAY 1.595745 (-5288 1152);
PAINT PURPLE (-5288 1152);
QUIT
